%FSTAX25Y25*%
%MOIN*%
%SFA1B1*%

%IPPOS*%
%ADD10C,0.008000*%
%ADD14C,0.010000*%
%ADD18C,0.006000*%
%ADD22C,0.005000*%
%ADD24C,0.009000*%
%ADD26R,0.039370X0.037400*%
%ADD27R,0.028350X0.039370*%
%ADD28R,0.064960X0.051180*%
%ADD29R,0.017720X0.054330*%
%ADD30R,0.055910X0.061020*%
%ADD31R,0.070870X0.074800*%
%ADD32R,0.039370X0.074800*%
%ADD33R,0.019680X0.090550*%
%ADD34R,0.078740X0.098430*%
%ADD35R,0.086610X0.041340*%
%ADD36R,0.041340X0.039370*%
%ADD37R,0.019680X0.035430*%
%ADD38O,0.057090X0.017720*%
%ADD39R,0.077560X0.022440*%
%ADD40R,0.025590X0.041340*%
%ADD41R,0.051180X0.074800*%
%ADD42R,0.039370X0.090550*%
%ADD43R,0.039370X0.070870*%
%ADD44R,0.053150X0.027560*%
%ADD45R,0.027560X0.045280*%
%ADD46R,0.041340X0.045280*%
%ADD47R,0.050000X0.200000*%
%ADD48R,0.057090X0.037400*%
%ADD49R,0.023620X0.025590*%
%ADD50R,0.135830X0.135830*%
%ADD51O,0.011810X0.027560*%
%ADD52O,0.027560X0.011810*%
%ADD53R,0.028000X0.165000*%
%ADD54R,0.028000X0.126000*%
%ADD55R,0.031500X0.066930*%
%ADD56R,0.070870X0.009840*%
%ADD57R,0.009840X0.022640*%
%ADD58R,0.026570X0.009840*%
%ADD59R,0.038580X0.034250*%
%ADD60R,0.212600X0.114170*%
%ADD61R,0.200790X0.322840*%
%ADD62R,0.096460X0.124020*%
%ADD63R,0.033470X0.039370*%
%ADD64R,0.057090X0.045280*%
%ADD65R,0.037400X0.039370*%
%ADD66R,0.025200X0.026770*%
%ADD67R,0.053150X0.066930*%
%ADD68R,0.009840X0.061020*%
%ADD69R,0.061020X0.009840*%
%ADD70R,0.066930X0.053150*%
%ADD71R,0.045280X0.057090*%
%ADD72R,0.026770X0.025200*%
%ADD73R,0.039370X0.033470*%
%ADD74R,0.039370X0.028350*%
%ADD75R,0.025590X0.023620*%
%ADD76R,0.082870X0.044090*%
%ADD140C,0.120000*%
%ADD147C,0.020000*%
%ADD148C,0.015000*%
%ADD149C,0.016000*%
%ADD150R,0.110430X0.066930*%
%ADD151R,0.105320X0.067910*%
%ADD152C,0.250000*%
%ADD153C,0.031500*%
%ADD154C,0.065980*%
%ADD155C,0.075000*%
%ADD156C,0.098430*%
%ADD157O,0.196850X0.098430*%
%ADD158O,0.177170X0.088580*%
%ADD159O,0.088580X0.177170*%
%ADD160C,0.112000*%
%ADD161C,0.021660*%
%ADD162C,0.055000*%
%ADD163R,0.055000X0.055000*%
%ADD164C,0.050000*%
%ADD165C,0.016000*%
%LNgrandmaster-1*%
%LPD*%
G36*
X1299213Y0850394D02*
X1246063D01*
Y0889764*
X1299213*
Y0850394*
G37*
G36*
X0975429Y0846934D02*
X0976025Y0846536D01*
X0976727Y0846396*
X1032732*
X1033434Y0846536*
X1034029Y0846934*
X1035298Y0848202*
X1035696Y0848798*
X1035835Y08495*
Y0849527*
X1036573*
X10611Y0825*
Y0783*
X10493Y07712*
X1034585*
X1034478Y0771349*
X1034363Y07717*
X1034696Y0772198*
X1034835Y07729*
Y0775393*
X1036654*
Y0781521*
X1029346*
Y0775393*
X1031165*
Y07729*
X1031304Y0772198*
X1031637Y07717*
X1031522Y0771349*
X1031415Y07712*
X1024084*
X1023978Y0771349*
X1023863Y07717*
X1024196Y0772198*
X1024335Y07729*
Y0775393*
X1026154*
Y0781521*
X1020223*
X1020016Y0782021*
X102044Y0782444*
X1021236*
X1021414Y0782479*
X1026154*
Y0783708*
X1029346*
Y0782479*
X1036654*
Y0783708*
X103744*
X1037827Y078332*
X1038423Y0782923*
X1039125Y0782783*
X1039417*
X1039771Y0782429*
Y0782105*
Y0781605*
Y0776869*
X1045229*
Y0777547*
X1049382*
X1050084Y0777686*
X105068Y0778084*
X1051077Y077868*
X1051217Y0779382*
X1051077Y0780084*
X105068Y078068*
X1050084Y0781077*
X1049382Y0781217*
X1045583*
X1045229Y0781571*
Y0781894*
Y0782395*
Y0787131*
X1039771*
X1039271Y0786993*
X1038902Y0787239*
X10382Y0787379*
X1036654*
Y0788607*
X1029346*
Y0787379*
X1026154*
Y0788607*
X1018846*
Y0785887*
X1018382Y0785577*
X1016502Y0783698*
X1016104Y0783102*
X1015965Y07824*
Y0781894*
X1011271*
Y0776869*
X1016729*
Y0777585*
X1017331Y0777704*
X1017926Y0778102*
X1018384Y077856*
X1018846Y0778369*
Y0775393*
X1020665*
Y07729*
X1020804Y0772198*
X1021137Y07717*
X1021022Y0771349*
X1020916Y07712*
X100709*
X1006823Y07717*
X1007007Y0771976*
X1007131Y07726*
X1007007Y0773224*
X1006826Y0773496*
Y0775393*
X1009154*
Y0781521*
X1001846*
Y0775393*
X1004175*
Y0773496*
X1003993Y0773224*
X1003869Y07726*
X1003993Y0771976*
X1004177Y07717*
X100391Y07712*
X0996485*
X0996351Y0771459*
X0996289Y07717*
X0996607Y0772176*
X0996731Y07728*
X0996607Y0773424*
X0996325Y0773846*
Y0775393*
X0998654*
Y0781521*
X0991346*
Y0775393*
X0993674*
Y0773547*
X0993593Y0773424*
X0993469Y07728*
X0993593Y0772176*
X0993911Y07717*
X0993849Y0771459*
X0993715Y07712*
X08818*
X08663Y07867*
Y0802695*
X0875825Y081222*
X087628Y0812129*
X0877854*
X0878397Y0812237*
X0878857Y0812545*
X0879164Y0813005*
X0879272Y0813547*
X0879164Y081409*
X0878869Y0814532*
X0879164Y0814973*
X0879272Y0815516*
X0879164Y0816058*
X0878857Y0816518*
X0878397Y0816826*
X0877854Y0816934*
X087628*
X0875737Y0816826*
X0875708Y0816807*
X0874481*
X0873974Y0816706*
X0873544Y0816418*
X0866762Y0809636*
X08663Y0809828*
Y0813326*
X0871067Y0818093*
X087599*
X087628Y0818035*
X0877854*
X0878397Y0818143*
X0878857Y081845*
X0879164Y081891*
X0879272Y0819453*
X0879164Y0819995*
X0878869Y0820437*
X0879164Y0820879*
X0879272Y0821421*
X0879164Y0821964*
X0878857Y0822424*
X0878397Y0822731*
X0877854Y0822839*
X087628*
X0875815Y0822747*
X0866451*
X08663Y0822871*
Y08329*
X08889Y08555*
X0966863*
X0975429Y0846934*
G37*
G36*
X1279528Y0770669D02*
X1234252D01*
X1232283Y0768701*
Y0749016*
X121063*
X1210108Y0748493*
X1209646Y0748685*
Y0777559*
X1244094*
X1245079Y0778543*
Y0797244*
X1279528*
Y0770669*
G37*
G36*
X1293307Y0651575D02*
X1271653Y0629921D01*
X1265354*
Y065944*
X1265446*
Y066356*
X1265354*
Y066544*
X1265446*
Y066956*
X1265354*
Y067044*
X1265446*
Y067456*
X1265354*
Y067594*
X1265446*
Y0679225*
X1267836Y0681616*
X1268224Y0681693*
X1268496Y0681875*
X1269566*
Y0679232*
X1274001*
Y0684768*
X1274389Y0685039*
X1274611*
X1274999Y0684768*
Y0679232*
X1279434*
Y0684768*
X1279822Y0685039*
X1286111*
X1286499Y0684768*
Y0679232*
X1290934*
Y0684768*
X1291322Y0685039*
X1293307*
Y0651575*
G37*
%LNgrandmaster-2*%
%LPC*%
G36*
X12725Y0886771D02*
X1271006Y0886574D01*
X1269615Y0885997*
X1268419Y0885081*
X1267502Y0883885*
X1266926Y0882493*
X1266729Y0881*
X1266926Y0879506*
X1267502Y0878115*
X1268419Y0876919*
X1269615Y0876003*
X1271006Y0875426*
X12725Y0875229*
X1273993Y0875426*
X1275385Y0876003*
X1276581Y0876919*
X1277497Y0878115*
X1278074Y0879506*
X1278271Y0881*
X1278074Y0882493*
X1277497Y0883885*
X1276581Y0885081*
X1275385Y0885997*
X1273993Y0886574*
X12725Y0886771*
G37*
G36*
X1289035Y0865117D02*
X1287542Y0864921D01*
X128615Y0864344*
X1284955Y0863427*
X1284038Y0862232*
X1283461Y086084*
X1283265Y0859346*
X1283461Y0857853*
X1284038Y0856461*
X1284955Y0855266*
X128615Y0854349*
X1287542Y0853773*
X1289035Y0853576*
X1290529Y0853773*
X1291921Y0854349*
X1293116Y0855266*
X1294033Y0856461*
X1294609Y0857853*
X1294806Y0859346*
X1294609Y086084*
X1294033Y0862232*
X1293116Y0863427*
X1291921Y0864344*
X1290529Y0864921*
X1289035Y0865117*
G37*
G36*
X1255965D02*
X1254471Y0864921D01*
X1253079Y0864344*
X1251884Y0863427*
X1250967Y0862232*
X1250391Y086084*
X1250194Y0859346*
X1250391Y0857853*
X1250967Y0856461*
X1251884Y0855266*
X1253079Y0854349*
X1254471Y0853773*
X1255965Y0853576*
X1257458Y0853773*
X125885Y0854349*
X1260045Y0855266*
X1260962Y0856461*
X1261539Y0857853*
X1261735Y0859346*
X1261539Y086084*
X1260962Y0862232*
X1260045Y0863427*
X125885Y0864344*
X1257458Y0864921*
X1255965Y0865117*
G37*
G36*
X09613Y0850631D02*
X0960676Y0850507D01*
X0960251Y0850224*
X09557*
X0955232Y085013*
X0954835Y0849865*
X0953997Y0849028*
X0953459Y0849196*
X0953154Y0849654*
X0952624Y0850007*
X0952Y0850131*
X0951376Y0850007*
X0950846Y0849654*
X0950493Y0849124*
X0950369Y08485*
X0950493Y0847876*
X0950846Y0847346*
X0951304Y0847041*
X0951472Y0846503*
X0950023Y0845053*
X0949758Y0844656*
X0949678Y0844257*
X0947406*
X0947301Y0844344*
X0947153Y0844847*
X0947507Y0845376*
X0947631Y0846*
X0947507Y0846624*
X0947153Y0847153*
X0946624Y0847507*
X0946Y0847631*
X0945376Y0847507*
X0944847Y0847153*
X0944661Y0846876*
X0944623Y0846863*
X0944083Y084691*
X0943853Y0847254*
X0943324Y0847607*
X09427Y0847731*
X0942076Y0847607*
X0941547Y0847254*
X0941508Y0847197*
X0941011Y0847148*
X0940194Y0847965*
X0939797Y084823*
X0939328Y0848324*
X09368*
X0936332Y084823*
X0935935Y0847965*
X0934776Y0846807*
X0934276Y0846707*
X0933747Y0846354*
X0933393Y0845824*
X0933269Y08452*
X0933357Y0844757*
X093305Y0844257*
X0929558*
Y0836643*
X09293Y0836431*
X0928676Y0836307*
X0928146Y0835954*
X0927793Y0835424*
X0927669Y08348*
X0927793Y0834176*
X0928146Y0833646*
X0928676Y0833293*
X09293Y0833169*
X0929924Y0833293*
X0930274Y0833527*
X0930774Y0833295*
Y0831396*
X0930593Y0831124*
X0930469Y08305*
X0930593Y0829876*
X0930947Y0829346*
X0931476Y0828993*
X09321Y0828869*
X0932724Y0828993*
X0933253Y0829346*
X0933607Y0829876*
X0933731Y08305*
X0933607Y0831124*
X0933426Y0831396*
Y083557*
X0934964*
X0935095*
X0935464*
X0937151*
X0937231Y083517*
X0937496Y0834774*
X0943035Y0829235*
X0943432Y082897*
X09439Y0828876*
X0947151*
X0947576Y0828593*
X09482Y0828469*
X0948824Y0828593*
X0949354Y0828946*
X0949707Y0829476*
X0949831Y08301*
X0949707Y0830724*
X0949354Y0831254*
X0948824Y0831607*
X09482Y0831731*
X0947576Y0831607*
X0947151Y0831324*
X0944407*
X0940622Y0835108*
X0940664Y0835209*
X0941001Y083557*
X0941369*
X0946775*
X0946906*
X0947275*
X0947406*
X095268*
X0952812*
X095318Y0835253*
Y0833905*
X0952678Y0833805*
X0952149Y0833451*
X0951795Y0832922*
X0951671Y0832298*
X0951795Y0831674*
X0952149Y0831144*
X0952678Y0830791*
X0953302Y0830666*
X0953926Y0830791*
X0954456Y0831144*
X0954809Y0831674*
X0954934Y0832298*
X0954809Y0832922*
X095469Y0833102*
X0954957Y0833602*
X0958717*
Y0844257*
X0953394*
X0953187Y0844757*
X0956207Y0847777*
X0960251*
X0960676Y0847493*
X09613Y0847369*
X0961924Y0847493*
X0962453Y0847847*
X0962807Y0848376*
X0962931Y0849*
X0962807Y0849624*
X0962453Y0850154*
X0961924Y0850507*
X09613Y0850631*
G37*
G36*
X08961Y0843131D02*
X0895476Y0843007D01*
X0894946Y0842653*
X0894593Y0842124*
X0894469Y08415*
X0894593Y0840876*
X0894675Y0840753*
X0894557Y0840376*
X0894468Y0840253*
X0890519*
Y0839499*
X0889636*
X0889324Y0839707*
X08887Y0839831*
X0888076Y0839707*
X0887547Y0839353*
X0887193Y0838824*
X0887069Y08382*
X0887193Y0837576*
X0887547Y0837047*
X0888076Y0836693*
X08887Y0836569*
X0889324Y0836693*
X0889556Y0836848*
X0890519*
Y0832747*
X0891237*
Y0828451*
X0891111Y0828263*
X0891004Y0827721*
Y0826146*
X0891111Y0825603*
X0891419Y0825143*
X0891879Y0824836*
X0892421Y0824728*
X0892964Y0824836*
X0893406Y0825131*
X0893847Y0824836*
X089439Y0824728*
X0894932Y0824836*
X0895392Y0825143*
X08957Y0825603*
X0895808Y0826146*
Y0827408*
X0897365Y0828966*
X089763Y0829362*
X0897723Y0829831*
Y0832747*
X0898481*
Y0836094*
Y0840253*
X0897732*
X0897525Y0840753*
X0897607Y0840876*
X0897731Y08415*
X0897607Y0842124*
X0897254Y0842653*
X0896724Y0843007*
X08961Y0843131*
G37*
G36*
X09735Y0836231D02*
X0972876Y0836107D01*
X0972604Y0835925*
X097057*
Y0836118*
X096523*
Y0831625*
X096473Y0831266*
X09644Y0831331*
X0963776Y0831207*
X0963247Y0830853*
X0962893Y0830324*
X0962769Y08297*
X0962893Y0829076*
X0963247Y0828547*
X0963776Y0828193*
X09644Y0828069*
X0965024Y0828193*
X0965553Y0828547*
X0965907Y0829076*
X0966031Y08297*
X0965956Y0830081*
X0966291Y0830581*
X097057*
Y0833274*
X0972604*
X0972876Y0833093*
X09735Y0832969*
X0974124Y0833093*
X0974654Y0833447*
X0975007Y0833976*
X0975131Y08346*
X0975007Y0835224*
X0974654Y0835754*
X0974124Y0836107*
X09735Y0836231*
G37*
G36*
X0888484Y0829138D02*
X0887942Y082903D01*
X08875Y0828735*
X0887058Y082903*
X0886516Y0829138*
X0885973Y082903*
X0885513Y0828723*
X0885206Y0828263*
X0885098Y0827721*
Y0826146*
X0885206Y0825603*
X0885513Y0825143*
X0885973Y0824836*
X0886516Y0824728*
X0887058Y0824836*
X08875Y0825131*
X0887942Y0824836*
X0888484Y0824728*
X0889027Y0824836*
X0889487Y0825143*
X0889794Y0825603*
X0889902Y0826146*
Y0827721*
X0889794Y0828263*
X0889487Y0828723*
X0889027Y082903*
X0888484Y0829138*
G37*
G36*
X0882579D02*
X0882036Y082903D01*
X0881594Y0828735*
X0881153Y082903*
X088061Y0829138*
X0880068Y082903*
X0879608Y0828723*
X08793Y0828263*
X0879192Y0827721*
Y0826146*
X08793Y0825603*
X0879608Y0825143*
X0880068Y0824836*
X088061Y0824728*
X0881153Y0824836*
X0881594Y0825131*
X0882036Y0824836*
X0882579Y0824728*
X0883121Y0824836*
X0883581Y0825143*
X0883889Y0825603*
X0883996Y0826146*
Y0827721*
X0883889Y0828263*
X0883581Y0828723*
X0883121Y082903*
X0882579Y0829138*
G37*
G36*
X09243Y0831331D02*
X0923676Y0831207D01*
X0923147Y0830853*
X0922793Y0830324*
X0922669Y08297*
X0922793Y0829076*
X0923147Y0828547*
X0923676Y0828193*
X09243Y0828069*
X0924924Y0828193*
X0925453Y0828547*
X0925807Y0829076*
X0925931Y08297*
X0925807Y0830324*
X0925453Y0830853*
X0924924Y0831207*
X09243Y0831331*
G37*
G36*
X09365Y0829331D02*
X0935876Y0829207D01*
X0935347Y0828854*
X0934993Y0828324*
X0934869Y08277*
X0934993Y0827076*
X0935347Y0826546*
X0935876Y0826193*
X09365Y0826069*
X0937124Y0826193*
X0937654Y0826546*
X0938007Y0827076*
X0938131Y08277*
X0938007Y0828324*
X0937654Y0828854*
X0937124Y0829207*
X09365Y0829331*
G37*
G36*
X09735Y0828131D02*
X0972876Y0828007D01*
X0972346Y0827654*
X0971993Y0827124*
X0971869Y08265*
X0971993Y0825876*
X0972346Y0825346*
X0972876Y0824993*
X09735Y0824869*
X0974124Y0824993*
X0974654Y0825346*
X0975007Y0825876*
X0975131Y08265*
X0975007Y0827124*
X0974654Y0827654*
X0974124Y0828007*
X09735Y0828131*
G37*
G36*
X0908619Y082767D02*
X0903082D01*
Y0822905*
X0902911Y0822871*
X0902382Y0822518*
X0902029Y0821988*
X0901983Y0821757*
X0901004Y0820778*
X0900519*
X090011Y0821278*
X0900138Y0821421*
X090003Y0821964*
X0899735Y0822406*
X090003Y0822847*
X0900138Y082339*
X090003Y0823932*
X0899723Y0824392*
X0899263Y08247*
X089872Y0824808*
X0897146*
X0896603Y08247*
X0896143Y0824392*
X0895836Y0823932*
X0895728Y082339*
X0895836Y0822847*
X0896131Y0822406*
X0895836Y0821964*
X0895728Y0821421*
X0895836Y0820879*
X0896131Y0820437*
X0895836Y0819995*
X0895728Y0819453*
X0895836Y081891*
X0896131Y0818468*
X0895836Y0818027*
X0895728Y0817484*
X0895836Y0816942*
X0896143Y0816482*
X0896603Y0816174*
X0897146Y0816066*
X089872*
X0899263Y0816174*
X0899392Y0816261*
X0902484*
X0902952Y0816354*
X0903349Y0816619*
X0906393Y0819663*
X0906893Y0819456*
Y0815076*
X0906588Y0814771*
X0899392*
X0899263Y0814857*
X089872Y0814965*
X0897146*
X0896603Y0814857*
X0896143Y081455*
X0895836Y081409*
X0895728Y0813547*
X0895836Y0813005*
X0896131Y0812563*
X0895836Y0812121*
X0895728Y0811579*
X0895836Y0811036*
X0896131Y0810594*
X0895836Y0810153*
X0895728Y080961*
X0895836Y0809068*
X0896143Y0808608*
X0896603Y08083*
X0897146Y0808192*
X089872*
X0898777Y0808204*
X0899277Y0807793*
Y0806121*
X0898777Y080597*
X0898654Y0806153*
X0898388Y0806331*
X0898365Y0806365*
X0898082Y0806649*
X0897685Y0806914*
X0897217Y0807007*
X0895777*
X08957Y0807397*
X0895392Y0807857*
X0894932Y0808164*
X089439Y0808272*
X0893847Y0808164*
X0893406Y0807869*
X0892964Y0808164*
X0892421Y0808272*
X0891879Y0808164*
X0891437Y0807869*
X0890995Y0808164*
X0890453Y0808272*
X088991Y0808164*
X0889468Y0807869*
X0889027Y0808164*
X0888484Y0808272*
X0887942Y0808164*
X08875Y0807869*
X0887058Y0808164*
X0886516Y0808272*
X0885973Y0808164*
X0885532Y0807869*
X088509Y0808164*
X0884547Y0808272*
X0884005Y0808164*
X0883563Y0807869*
X0883121Y0808164*
X0882579Y0808272*
X0882036Y0808164*
X0881576Y0807857*
X0881269Y0807397*
X0881161Y0806854*
Y080528*
X0881249Y0804839*
X0880979Y0804339*
X0880844*
X0880375Y0804246*
X0879978Y080398*
X0875751Y0799753*
X0873519*
Y0795594*
Y0792747*
Y0792512*
X0873128Y0792473*
X0873002Y0792548*
X0872907Y0793024*
X0872554Y0793553*
X0872024Y0793907*
X08714Y0794031*
X0870776Y0793907*
X0870247Y0793553*
X0869893Y0793024*
X0869769Y07924*
X0869893Y0791776*
X0870247Y0791247*
X0870776Y0790893*
X08714Y0790769*
X0872024Y0790893*
X0872554Y0791247*
X0872907Y0791776*
X0872976Y0792123*
X0873507Y0792254*
X0873519Y0792247*
X0873821*
X0874174Y0791894*
Y0791772*
X0874146Y0791753*
X0873793Y0791224*
X0873669Y07906*
X0873793Y0789976*
X0874146Y0789446*
X0874676Y0789093*
X08753Y0788969*
X0875924Y0789093*
X0876453Y0789446*
X0876807Y0789976*
X0876931Y07906*
X0876826Y0791132*
Y0792247*
X0877481*
Y0795594*
Y0797588*
X0877519Y0797614*
X0878019Y0797346*
Y0792247*
X0878675*
Y07916*
X0878775Y0791093*
X0879063Y0790663*
X0879079Y0790646*
X0879193Y0790076*
X0879547Y0789546*
X0880076Y0789193*
X08807Y0789069*
X0881324Y0789193*
X0881853Y0789546*
X0882207Y0790076*
X0882331Y07907*
X0882207Y0791324*
X0881925Y0791747*
X0881981Y0792247*
Y0795594*
Y0797588*
X0882019Y0797614*
X0882519Y0797346*
Y0792247*
X088393*
X0883957Y0792112*
X0884244Y0791682*
X0885929Y0789996*
X0885993Y0789676*
X0886347Y0789147*
X0886876Y0788793*
X08875Y0788669*
X0888124Y0788793*
X0888653Y0789147*
X0888933Y0789565*
X0889337Y0789632*
X0889504Y078961*
X0889546Y0789546*
X0890076Y0789193*
X08907Y0789069*
X0891324Y0789193*
X0891854Y0789546*
X0892207Y0790076*
X0892331Y07907*
X0892207Y0791324*
X0891854Y0791854*
X0891324Y0792207*
X0891004Y0792271*
X0890981Y0792293*
Y0795594*
Y0798023*
X0892384Y0799425*
X0892846Y0799234*
Y079648*
X0900154*
Y0798508*
X0900408Y0798678*
X0901365Y0799635*
X090163Y0800032*
X0901655Y0800154*
X090183Y0800582*
X0903174*
Y0799949*
X0901997Y0798771*
X0901676Y0798707*
X0901147Y0798353*
X0900793Y0797824*
X0900669Y07972*
X0900793Y0796576*
X0901147Y0796046*
X0901676Y0795693*
X09023Y0795569*
X0902924Y0795693*
X0903454Y0796046*
X0903807Y0796576*
X0903871Y0796897*
X0905011Y0798037*
X0905414Y0797914*
X0905519Y0797837*
X0905847Y0797346*
X0906376Y0796993*
X0907Y0796869*
X0907624Y0796993*
X0908154Y0797346*
X0908507Y0797876*
X0908631Y07985*
X0908565Y0798832*
X0908658Y0798971*
X09087Y0799035*
X0909017Y0799393*
X0911174*
Y0795549*
X0908821Y0793196*
X0908376Y0793107*
X0907847Y0792754*
X0907493Y0792224*
X0907369Y07916*
X0907493Y0790976*
X0907847Y0790447*
X0908376Y0790093*
X0909Y0789969*
X0909624Y0790093*
X0910153Y0790447*
X0910507Y0790976*
X0910546Y0791172*
X0913437Y0794063*
X0913725Y0794493*
X0913826Y0795*
Y0799393*
X0916154*
Y0805521*
X0908846*
X0908794Y0805999*
Y0806001*
X0908846Y0806479*
X0916154*
Y080832*
X0917771*
Y0806606*
X0923229*
Y0811631*
X0917771*
Y0810767*
X0916154*
Y0812607*
X0908846*
Y0810873*
X090717*
Y0812339*
X0907563Y0812417*
X090796Y0812682*
X0908623Y0813346*
X0913021*
Y0820654*
X0907235*
X0907074Y082085*
Y082233*
X0908619*
Y082767*
G37*
G36*
X0914918D02*
X0909381D01*
Y082233*
X0914918*
Y0824677*
X0920139*
X0920524Y0824177*
X0920469Y08239*
X0920593Y0823276*
X0920947Y0822746*
X0921476Y0822393*
X09221Y0822269*
X0922724Y0822393*
X0923254Y0822746*
X0923607Y0823276*
X0923678Y0823635*
X0924221Y0823799*
X092787Y0820151*
X0928267Y0819885*
X0928735Y0819792*
X0929558*
Y0816673*
X093263*
X093268Y0816422*
X0932945Y0816025*
X0935635Y0813335*
X0936032Y081307*
X09365Y0812976*
X0958151*
X0958576Y0812693*
X09592Y0812569*
X0959824Y0812693*
X0960353Y0813046*
X0960707Y0813576*
X0960831Y08142*
X0960707Y0814824*
X0960353Y0815353*
X0959824Y0815707*
X09592Y0815831*
X0958576Y0815707*
X0958151Y0815423*
X0937007*
X093622Y081621*
X0936411Y0816673*
X0940869*
X0941001Y0816672*
X0941369*
X0941501Y0816673*
X0946775*
X0946906Y0816672*
X0947275*
X0947406Y0816673*
X0952812*
Y0825359*
X0947406*
X0947275*
X0946906*
X0946775*
X0941501*
X0941369*
X0941001*
X0940869*
X0935464*
X0935095*
X0934964*
X0929558*
Y082263*
X0929058Y0822423*
X0924716Y0826765*
X0924319Y082703*
X0923851Y0827124*
X0914918*
Y082767*
G37*
G36*
X09188Y0823431D02*
X0918176Y0823307D01*
X0917647Y0822954*
X0917293Y0822424*
X0917169Y08218*
X0917293Y0821176*
X0917307Y0821154*
X091704Y0820654*
X091398*
Y0813346*
X0920107*
Y0818664*
X0920125Y0818757*
Y0820904*
X0920307Y0821176*
X0920431Y08218*
X0920307Y0822424*
X0919954Y0822954*
X0919424Y0823307*
X09188Y0823431*
G37*
G36*
X10468Y0815531D02*
X1046176Y0815407D01*
X1045646Y0815053*
X1045293Y0814524*
X1045169Y08139*
X1045195Y0813769*
X1044316Y0812891*
X1043761Y0813043*
X1043703Y0813269*
X1043707Y0813276*
X1043831Y08139*
X1043707Y0814524*
X1043353Y0815053*
X1042824Y0815407*
X10422Y0815531*
X1041576Y0815407*
X1041047Y0815053*
X1040693Y0814524*
X1040569Y08139*
X1040693Y0813276*
X1040874Y0813004*
Y0812442*
X1038764Y0810332*
X103644*
Y0806054*
X104056*
Y0808378*
X1041978Y0809797*
X104244Y0809605*
Y0806054*
X104656*
Y0810332*
X1046213*
X1046006Y0810832*
X1047622Y0812448*
X1047716Y0812588*
X1047954Y0812747*
X1048307Y0813276*
X1048431Y08139*
X1048307Y0814524*
X1047954Y0815053*
X1047424Y0815407*
X10468Y0815531*
G37*
G36*
X0993Y0814131D02*
X0992376Y0814007D01*
X0991846Y0813653*
X0991493Y0813124*
X0991369Y08125*
X0991493Y0811876*
X0991846Y0811347*
X0992376Y0810993*
X0993Y0810869*
X0993624Y0810993*
X0994153Y0811347*
X0994507Y0811876*
X0994631Y08125*
X0994507Y0813124*
X0994153Y0813653*
X0993624Y0814007*
X0993Y0814131*
G37*
G36*
X09797Y0825531D02*
X0979076Y0825407D01*
X0978547Y0825054*
X0978193Y0824524*
X0978069Y08239*
X0978193Y0823276*
X0978364Y082302*
X0978012Y0822646*
X0977752*
X097394*
Y0818369*
X0976264*
X098427Y0810363*
X09847Y0810075*
X0985207Y0809974*
X0986204*
X0986476Y0809793*
X09871Y0809669*
X0987724Y0809793*
X0988253Y0810147*
X0988607Y0810676*
X0988731Y08113*
X0988607Y0811924*
X0988253Y0812453*
X0987724Y0812807*
X09871Y0812931*
X0986476Y0812807*
X0986204Y0812626*
X0985756*
X0984886Y0813496*
X0985031Y0813974*
X0985124Y0813993*
X0985653Y0814347*
X0986007Y0814876*
X0986131Y08155*
X0986007Y0816124*
X0985653Y0816654*
X0985124Y0817007*
X09845Y0817131*
X0983876Y0817007*
X0983851Y0816991*
X0983491Y0817351*
X0983507Y0817376*
X0983631Y0818*
X0983507Y0818624*
X0983154Y0819153*
X0982624Y0819507*
X0982Y0819631*
X0981376Y0819507*
X0980847Y0819153*
X0980642Y0818848*
X0980077Y0818723*
X0980019Y0818737*
X0980066Y0819288*
X0980153Y0819347*
X0980507Y0819876*
X0980631Y08205*
X0980507Y0821124*
X0980153Y0821653*
X0979928Y0821804*
X0980034Y0822335*
X0980324Y0822393*
X0980853Y0822746*
X0981207Y0823276*
X0981331Y08239*
X0981207Y0824524*
X0980853Y0825054*
X0980324Y0825407*
X09797Y0825531*
G37*
G36*
X0895091Y0824091D02*
X0879909D01*
Y0808909*
X0895091*
Y0824091*
G37*
G36*
X0877854Y0811028D02*
X087628D01*
X0875737Y081092*
X0875277Y0810613*
X087497Y0810153*
X0874862Y080961*
X087497Y0809068*
X0875277Y0808608*
X0875737Y08083*
X087628Y0808192*
X0877854*
X0878397Y08083*
X0878857Y0808608*
X0879164Y0809068*
X0879272Y080961*
X0879164Y0810153*
X0878857Y0810613*
X0878397Y081092*
X0877854Y0811028*
G37*
G36*
X10059Y0815531D02*
X1005276Y0815407D01*
X1004747Y0815053*
X1004393Y0814524*
X1004329Y0814203*
X1003368Y0813242*
X100308Y0812812*
X1003002Y0812418*
X100033*
Y0806881*
X100567*
Y0811796*
X1006203Y0812329*
X1006524Y0812393*
X1007053Y0812747*
X1007407Y0813276*
X1007531Y08139*
X1007407Y0814524*
X1007053Y0815053*
X1006524Y0815407*
X10059Y0815531*
G37*
G36*
X09482Y0812331D02*
X0947576Y0812207D01*
X0947046Y0811854*
X0946693Y0811324*
X0946569Y08107*
X0946584Y0810621*
X094637Y08103*
X0946276Y0809831*
Y0808636*
X0940007*
Y0806796*
X0936691*
X0936524Y0806907*
X09359Y0807031*
X0935276Y0806907*
X0934746Y0806553*
X0934393Y0806024*
X0934269Y08054*
X0934393Y0804776*
X0934746Y0804247*
X0935276Y0803893*
X09359Y0803769*
X0936524Y0803893*
X0937053Y0804247*
X0937122Y0804349*
X0940007*
Y080264*
Y0802509*
Y080214*
Y0802009*
Y0801186*
X0934605*
X0934124Y0801507*
X09335Y0801631*
X0932876Y0801507*
X0932347Y0801153*
X0931993Y0800624*
X0931869Y08*
X0931993Y0799376*
X0932347Y0798846*
X0932876Y0798493*
X09335Y0798369*
X0934124Y0798493*
X0934492Y0798739*
X0940007*
Y0797916*
Y0797784*
Y0797416*
Y0797284*
Y0793191*
Y079306*
Y0792691*
Y079256*
Y0790525*
X0936996*
X0936724Y0790707*
X09361Y0790831*
X0935476Y0790707*
X0934947Y0790353*
X0934593Y0789824*
X0934469Y07892*
X0934593Y0788576*
X0934947Y0788047*
X0935476Y0787693*
X09361Y0787569*
X0936724Y0787693*
X0936996Y0787875*
X0940007*
Y0786564*
X0946175*
Y0782868*
X0944566*
Y0777331*
X0949001*
Y0782868*
X0948825*
Y0786564*
X0954993*
Y0788404*
X095811*
X0958576Y0788093*
X09592Y0787969*
X0959824Y0788093*
X0960353Y0788447*
X0960707Y0788976*
X0960831Y07896*
X0960707Y0790224*
X0960353Y0790754*
X0959824Y0791107*
X09592Y0791231*
X0958576Y0791107*
X0958192Y0790851*
X0954993*
Y079256*
Y0792691*
Y079306*
Y0793191*
Y0794026*
X0955493Y0794076*
X0955847Y0793546*
X0956376Y0793193*
X0957Y0793069*
X0957624Y0793193*
X0958154Y0793546*
X0958507Y0794076*
X0958631Y07947*
X0958507Y0795324*
X0958154Y0795854*
X0957624Y0796207*
X0957123Y0796307*
X0955003Y0798427*
X0954993Y0798479*
Y080214*
X0949995*
X0949678Y0802509*
Y080264*
Y0808636*
X0948724*
Y0809173*
X0948824Y0809193*
X0949354Y0809546*
X0949707Y0810076*
X0949831Y08107*
X0949707Y0811324*
X0949354Y0811854*
X0948824Y0812207*
X09482Y0812331*
G37*
G36*
X10324Y0815531D02*
X1031776Y0815407D01*
X1031246Y0815053*
X1030893Y0814524*
X1030769Y08139*
X1030893Y0813276*
X1031174Y0812854*
Y0810332*
X103044*
Y0806054*
X103456*
Y0810332*
X1033825*
Y0813153*
X1033907Y0813276*
X1034031Y08139*
X1033907Y0814524*
X1033554Y0815053*
X1033024Y0815407*
X10324Y0815531*
G37*
G36*
X10263D02*
X1025676Y0815407D01*
X1025146Y0815053*
X1024793Y0814524*
X1024669Y08139*
X1024793Y0813276*
X1024975Y0813004*
Y0810332*
X102444*
Y0806054*
X102856*
Y0810332*
X1027625*
Y0813004*
X1027807Y0813276*
X1027931Y08139*
X1027807Y0814524*
X1027454Y0815053*
X1026924Y0815407*
X10263Y0815531*
G37*
G36*
X102302Y0828654D02*
X1016893D01*
Y0821346*
X1018631*
Y0814881*
X1018393Y0814524*
X1018269Y08139*
X1018393Y0813276*
X1018746Y0812747*
X1018984Y0812588*
X1019077Y0812448*
X1019674Y0811851*
Y0810332*
X101894*
Y0806054*
X102306*
Y0810332*
X1022326*
Y08124*
X1022225Y0812907*
X1021937Y0813337*
X1021505Y0813769*
X1021531Y08139*
X1021407Y0814524*
X1021282Y0814711*
Y0821346*
X102302*
Y0828654*
G37*
G36*
X10143Y0815531D02*
X1013676Y0815407D01*
X1013146Y0815053*
X1012793Y0814524*
X1012669Y08139*
X1012793Y0813276*
X1013146Y0812747*
X1013181Y0812723*
X101319Y0812678*
X1013478Y0812248*
X1014174Y0811551*
Y0810332*
X101344*
Y0806054*
X101756*
Y0810332*
X1016825*
Y08121*
X1016725Y0812607*
X1016437Y0813037*
X1015872Y0813602*
X1015931Y08139*
X1015807Y0814524*
X1015454Y0815053*
X1014924Y0815407*
X10143Y0815531*
G37*
G36*
X10105D02*
X1009876Y0815407D01*
X1009346Y0815053*
X1008993Y0814524*
X1008869Y08139*
X1008908Y0813705*
X1008775Y0813507*
X1008675Y0813*
Y0810332*
X100794*
Y0806054*
X101206*
Y0810332*
X1011325*
Y0812453*
X1011416Y0812588*
X1011654Y0812747*
X1012007Y0813276*
X1012131Y08139*
X1012007Y0814524*
X1011654Y0815053*
X1011124Y0815407*
X10105Y0815531*
G37*
G36*
X0972054Y0815221D02*
X0964746D01*
Y0809093*
X0969475*
Y0808496*
X0969293Y0808224*
X0969169Y08076*
X0969293Y0806976*
X0969646Y0806446*
X0970176Y0806093*
X09708Y0805969*
X0971424Y0806093*
X0971953Y0806446*
X0972307Y0806976*
X0972431Y08076*
X0972307Y0808224*
X0972126Y0808496*
Y0809757*
X097208Y0809986*
Y0810393*
X0972054Y0810521*
Y0815221*
G37*
G36*
X09188Y0799031D02*
X0918176Y0798907D01*
X0917647Y0798554*
X0917293Y0798024*
X0917169Y07974*
X0917293Y0796776*
X0917647Y0796246*
X0918176Y0795893*
X09188Y0795769*
X0919424Y0795893*
X0919954Y0796246*
X0920307Y0796776*
X0920431Y07974*
X0920307Y0798024*
X0919954Y0798554*
X0919424Y0798907*
X09188Y0799031*
G37*
G36*
X0900154Y079552D02*
X0892846D01*
Y0789393*
X0898273*
X0898503Y0789163*
X0898933Y0788875*
X089944Y0788774*
X0900004*
X0900276Y0788593*
X09009Y0788469*
X0901524Y0788593*
X0902054Y0788946*
X0902407Y0789476*
X0902531Y07901*
X0902407Y0790724*
X0902054Y0791254*
X0901524Y0791607*
X09009Y0791731*
X0900654Y0791682*
X0900154Y0792082*
Y079552*
G37*
%LNgrandmaster-3*%
%LPD*%
G54D10*
X0848685Y05125D02*
X0849685Y05115D01*
X0904803Y051345D02*
X0905Y0513647D01*
X0788351Y09022D02*
X07894D01*
X0787701Y090285D02*
X0788351Y09022D01*
X0783628Y090285D02*
X0787701D01*
X0874839Y0866571D02*
X0878768Y08705D01*
X0871Y0866571D02*
X0874839D01*
X0878768Y08705D02*
X0899079D01*
X09005Y08005D02*
Y0808949D01*
X0899543Y0799543D02*
X09005Y08005D01*
X08965Y0799543D02*
X0899543D01*
X0899839Y080961D02*
X09005Y0808949D01*
X0897933Y080961D02*
X0899839D01*
X0897933Y0811579D02*
X0902669D01*
X0875429Y0806067D02*
X088061D01*
X0874489Y0807007D02*
X0875429Y0806067D01*
X0874489Y0807007D02*
Y0810352D01*
X0972043Y0573591D02*
X0972799Y0572835D01*
X0996988Y058124D02*
Y0589456D01*
X0988583Y0572835D02*
X0996988Y058124D01*
X0972799Y0572835D02*
X0988583D01*
X0970693Y057165D02*
X0972043Y0573D01*
X0970693Y0564D02*
Y057165D01*
X1267Y0734323D02*
Y0742406D01*
X1263327Y073065D02*
X1267Y0734323D01*
X1246Y073065D02*
X1263327D01*
X1242579D02*
X1246D01*
X1238728Y07345D02*
X1242579Y073065D01*
X1234244Y07345D02*
X1238728D01*
X127787Y06885D02*
X1282244D01*
X1277217Y0687847D02*
X127787Y06885D01*
X1277217Y0687847D02*
Y0682D01*
X1288717D02*
Y0686874D01*
X1287091Y06885D02*
X1288717Y0686874D01*
X1282244Y06885D02*
X1287091D01*
X1234963Y083142D02*
X1237818D01*
X1232653Y082911D02*
X1234963Y083142D01*
X1232653Y0827153D02*
Y082911D01*
X1248059Y081761D02*
X1250152D01*
X1247942Y0817728D02*
X1248059Y081761D01*
X1241047Y0813488D02*
Y0815396D01*
X1240059Y08125D02*
X1241047Y0813488D01*
X12295Y08125D02*
X1240059D01*
X07008Y0884D02*
X0802D01*
X0683079Y0901721D02*
X07008Y0884D01*
X06826Y0882D02*
X07995D01*
X0662913Y0901687D02*
X06826Y0882D01*
X0662913Y0901687D02*
Y0904284D01*
X07354Y089D02*
X08075D01*
X0723413Y0901987D02*
X07354Y089D01*
X0723413Y0901987D02*
Y0904284D01*
X07176Y08875D02*
X0805D01*
X0703246Y0901854D02*
X07176Y08875D01*
X0703246Y0901854D02*
Y0904284D01*
X0683079Y0901721D02*
Y0904284D01*
X077645Y090535D02*
X0783628D01*
X0766636Y0915164D02*
X077645Y090535D01*
X0762358Y0915164D02*
X0766636D01*
X0832272Y0913972D02*
Y0917428D01*
X08176Y08993D02*
X0832272Y0913972D01*
X0768Y08993D02*
X08176D01*
X08137Y07582D02*
Y0762884D01*
X08099Y07544D02*
X08137Y07582D01*
X08099Y06732D02*
Y07544D01*
X0822Y0759D02*
X0822282Y0758718D01*
Y0752219D02*
Y0758718D01*
X082425Y0752219D02*
Y076175D01*
X0826219Y0746781D02*
Y0752219D01*
X0855746Y0740746D02*
X08566Y07416D01*
X0855746Y0736275D02*
Y0740746D01*
X08939Y07432D02*
Y0746D01*
Y07432D02*
X0897085Y0740015D01*
Y0736275D02*
Y0740015D01*
X0931933Y0683D02*
X09396D01*
X0940138Y0683538*
X0948218*
X09383Y06875D02*
X0940312Y0685488D01*
X0948199*
X0948218Y0685507*
X0951912Y0691412D02*
X09545Y0694D01*
X0948218Y0691412D02*
X0951912D01*
X10126Y06605D02*
X1017D01*
X1010744Y0662356D02*
X10126Y06605D01*
X1005906Y0662356D02*
X1010744D01*
X090585Y082085D02*
Y0825D01*
X0902484Y0817484D02*
X090585Y082085D01*
X0897933Y0817484D02*
X0902484D01*
X091215Y0825D02*
X091305Y08259D01*
X0923851*
X0928735Y0821016*
X0932327*
X093381Y0819533*
Y081689D02*
Y0819533D01*
Y081689D02*
X09365Y08142D01*
X09592*
X0959172Y0789628D02*
X09592Y07896D01*
X0952126Y0789628D02*
X0959172D01*
X08975Y0805D02*
Y08055D01*
X0897217Y0805783D02*
X08975Y08055D01*
X09045Y0809551D02*
X090757Y0806481D01*
X0907Y0798933D02*
X090757Y0799503D01*
X09045Y0809551D02*
Y080965D01*
X090757Y0799503D02*
Y0806481D01*
X0907Y07985D02*
Y0798933D01*
X0894566Y0805783D02*
X0897217D01*
X089439Y080596D02*
X0894566Y0805783D01*
X089439Y080596D02*
Y0806067D01*
X09125Y0809543D02*
X0920075D01*
X09205Y0809118*
X09045Y080965D02*
X0912394D01*
X09125Y0809543*
X0902669Y0811579D02*
X09045Y0809748D01*
Y080965D02*
Y0809748D01*
X0909957Y0816409D02*
Y0817D01*
X0907094Y0813547D02*
X0909957Y0816409D01*
X0897933Y0813547D02*
X0907094D01*
X12595Y081965D02*
X1269514D01*
X1271673Y081749*
Y0817201D02*
Y081749D01*
X1259429Y0819579D02*
X12595Y081965D01*
X1250152Y0819579D02*
X1259429D01*
X12595Y082685D02*
X1269514D01*
X1271673Y082901*
Y0829799*
X12595Y0826752D02*
Y082685D01*
X1254295Y0821547D02*
X12595Y0826752D01*
X1250152Y0821547D02*
X1254295D01*
X06635Y0910304D02*
Y0920146D01*
X0662913Y0909717D02*
X06635Y0910304D01*
X0683667D02*
Y0919646D01*
X0683079Y0909717D02*
X0683667Y0910304D01*
X0846281Y0555369D02*
X0846379D01*
X08455Y055615D02*
X0846281Y0555369D01*
X08455Y055615D02*
Y0556248D01*
X0846379Y0555369D02*
X08482Y0553548D01*
Y0539272D02*
Y0553548D01*
Y0539272D02*
X0849685Y0537787D01*
Y05115D02*
Y0537787D01*
X0904803Y0556051D02*
X0905Y0556248D01*
X0904803Y051345D02*
Y0556051D01*
X12225Y0718716D02*
Y0724512D01*
X1217512Y07295D02*
X12225Y0724512D01*
X1214756Y07295D02*
X1217512D01*
X1279488Y06885D02*
X1282244D01*
X12113Y0743784D02*
X1211851D01*
X1212868Y0742766*
Y0742215D02*
Y0742766D01*
Y0742215D02*
X121373Y0741353D01*
Y0740222D02*
Y0741353D01*
Y0740222D02*
X1214452Y07395D01*
X1214756*
X1217512*
X1223512Y07455*
X1230284*
X08935Y0874937D02*
Y08955D01*
X09135Y0874937D02*
Y08955D01*
X0934Y0874937D02*
Y0895D01*
X09335Y08955D02*
X0934Y0895D01*
X1010283Y08705D02*
Y0871051D01*
X1007585Y087375D02*
X1010283Y0871051D01*
X0997728Y087375D02*
X1007585D01*
X1055693Y0921D02*
X1064283D01*
Y09125D02*
Y0921D01*
D01*
X1108193D02*
X1120284D01*
Y0913D02*
Y0921D01*
Y0913D02*
D01*
X0886443Y0805994D02*
X0886516Y0806067D01*
X0886443Y0804142D02*
Y0805994D01*
X0885417Y0803115D02*
X0886443Y0804142D01*
X0880844Y0803115D02*
X0885417D01*
X08755Y0797772D02*
X0880844Y0803115D01*
X08755Y0797673D02*
Y0797772D01*
X089439Y0826933D02*
Y0827721D01*
X08965Y0829831*
Y0834827*
X0892421Y0826933D02*
X0892461Y0826972D01*
Y0834787*
X08925Y0834827*
X0888484Y080392D02*
Y0806067D01*
X0886079Y0801515D02*
X0888484Y080392D01*
X0883744Y0801515D02*
X0886079D01*
X088Y0797772D02*
X0883744Y0801515D01*
X088Y0797673D02*
Y0797772D01*
X0890453Y0803626D02*
Y0806067D01*
X088538Y0798553D02*
X0890453Y0803626D01*
X0885281Y0798553D02*
X088538D01*
X08845Y0797772D02*
X0885281Y0798553D01*
X08845Y0797673D02*
Y0797772D01*
X0892421Y0801193D02*
Y0806067D01*
X0889Y0797772D02*
X0892421Y0801193D01*
X0889Y0797673D02*
Y0797772D01*
X0783628Y090785D02*
X0792367D01*
X07924Y0907883*
X1004Y08669D02*
Y0869851D01*
X1002601Y087125D02*
X1004Y0869851D01*
X0997728Y087125D02*
X1002601D01*
X098175Y088125D02*
X0982Y0881D01*
X0976272Y088125D02*
X098175D01*
X0762172Y091535D02*
X0762358Y0915164D01*
X0830156Y0736275D02*
X0832124D01*
Y0721924D02*
Y0736275D01*
X08321Y07219D02*
X0832124Y0721924D01*
X0869526Y0732402D02*
Y0736275D01*
X08696Y0730217D02*
Y0732328D01*
X0869526Y0732402D02*
X08696Y0732328D01*
X08693Y07297D02*
Y0729916D01*
X08696Y0730217*
X10055Y06515D02*
Y0660264D01*
X1005592Y0660356*
X1005906*
X0832Y0848874D02*
X0832374Y08485D01*
X0838*
X09795Y0684D02*
Y06844D01*
X0975101Y0679601D02*
X09795Y0684D01*
X0964162Y0679601D02*
X0975101D01*
X1237012Y083139D02*
X1237848D01*
X1237818Y083142D02*
X1237848Y083139D01*
X12325Y0827D02*
Y0827371D01*
Y0827D02*
X1232653Y0827153D01*
X0976402Y0666902D02*
Y0667004D01*
X0974Y06645D02*
X0976402Y0666902D01*
X0970257Y06645D02*
X0974D01*
X0968935Y0665822D02*
X0970257Y06645D01*
X0964162Y0665822D02*
X0968935D01*
X0964162Y0701255D02*
X0969745D01*
X0971Y07*
X0851809Y0726809D02*
Y0736275D01*
X0849Y0724D02*
X0851809Y0726809D01*
X0861652Y0736275D02*
Y0746348D01*
X08615Y07465D02*
X0861652Y0746348D01*
X08615Y07465D02*
X0861576Y0746576D01*
X10055Y0678448D02*
Y068D01*
Y0678448D02*
X1005592Y0678356D01*
X1005906*
X09915Y0654D02*
D01*
X0978605D02*
X09915D01*
X0976626Y0655979D02*
X0978605Y0654D01*
X0964162Y0655979D02*
X0976626D01*
X0922464Y0675664D02*
X0948218D01*
X0918742Y0671942D02*
X0922464Y0675664D01*
X0918742Y06718D02*
Y0671942D01*
X0845904Y0763904D02*
X08485Y07665D01*
X0845904Y0752219D02*
Y0763904D01*
X08137Y0768317D02*
Y07757D01*
X1005906Y0676356D02*
X1011631D01*
X1012487Y06755*
X10125*
X0859Y0743567D02*
X0859683Y0742884D01*
X0859Y0743567D02*
Y0744D01*
X0859683Y0736275D02*
Y0742884D01*
X0972043Y0573D02*
Y0573591D01*
X0825443Y0854943D02*
X0830195D01*
X0832Y0856748*
X08245Y0854D02*
X0825443Y0854943D01*
X09545Y06895D02*
X0954528Y0689472D01*
X0964134*
X0964162Y0689444*
X0843935Y0752219D02*
Y0765435D01*
X08485Y077*
X0874489Y0810352D02*
X0875643Y0811506D01*
X0876994*
X0877067Y0811579*
X0964162Y0691412D02*
X0969912D01*
X0971Y06925*
X0853778Y0731722D02*
Y0736275D01*
Y0731722D02*
X0857Y07285D01*
X099108Y0679579D02*
X09935Y0682D01*
X099108Y0678448D02*
Y0679579D01*
X0990987Y0678356D02*
X099108Y0678448D01*
X0990158Y0678356D02*
X0990987D01*
X0948218Y0701255D02*
X0952745D01*
X09545Y06995*
X09359Y08054D02*
X0936117D01*
X0936289Y0805572*
X0942874*
X095743Y068157D02*
X0964162D01*
X09545Y06845D02*
X095743Y068157D01*
X0875349Y0813474D02*
X0876994D01*
X0877067Y0813547*
X0853778Y0791904D02*
X0875349Y0813474D01*
X0853778Y0752219D02*
Y0791904D01*
X0964162Y0677633D02*
X0970531D01*
X0971Y0677D02*
Y0677164D01*
X0970531Y0677633D02*
X0971Y0677164D01*
X08495Y0841D02*
X08625D01*
X0776671Y0681574D02*
X0787009D01*
X0787284Y06813*
X1066Y0861D02*
X10662Y08612D01*
X1075361Y0864003D02*
X1085Y0873643D01*
Y0879745*
X1233813Y0825484D02*
X1237848D01*
X1233328Y0825D02*
X1233813Y0825484D01*
X1229257Y0825D02*
X1233328D01*
X1227257Y0823D02*
X1229257Y0825D01*
X09795Y0666323D02*
Y06694D01*
X09794Y06695D02*
X09795Y06694D01*
X0976077Y06629D02*
X09795Y0666323D01*
X0969595Y06629D02*
X0976077D01*
X0968642Y0663853D02*
X0969595Y06629D01*
X0964162Y0663853D02*
X0968642D01*
X0776671Y0652046D02*
X0788746D01*
X08099Y06732*
X0813149Y0762884D02*
X08137D01*
X074685Y092035D02*
X0762172D01*
X07429Y09164D02*
X074685Y092035D01*
X0762122Y09129D02*
X0762172Y091285D01*
X07576Y09129D02*
X0762122D01*
X08235Y09021D02*
Y09022D01*
X0834832Y0913531*
Y0917428*
X0762172Y090285D02*
X0764403D01*
X0764889Y0902364*
X0764936*
X0768Y08993*
X1013278Y06635D02*
X1014022Y0662756D01*
X1005906Y0664356D02*
X1010816D01*
X1011672Y06635*
X1013278*
X1014022Y0662756D02*
X1014146D01*
X1005906Y0666356D02*
X1011631D01*
X1012487Y06655*
X10125*
X09475Y0805572D02*
Y0809831D01*
X09482Y0810531*
Y08107*
X0881337Y0752219D02*
Y0760363D01*
X08812Y07605D02*
X0881337Y0760363D01*
X09557Y0849D02*
X09613D01*
X0950888Y0844188D02*
X09557Y0849D01*
X0950043Y0839913D02*
X0950888Y0840758D01*
Y0844188*
X0938232Y0839913D02*
X0938361Y0839784D01*
Y0835639D02*
Y0839784D01*
X09439Y08301D02*
X09482D01*
X0938361Y0835639D02*
X09439Y08301D01*
X0933538Y0799962D02*
X0943465D01*
X09335Y08D02*
X0933538Y0799962D01*
X1230157Y08205D02*
X1232202D01*
X1235218Y0823516D02*
X1237848D01*
X1232202Y08205D02*
X1235218Y0823516D01*
X1229957Y08203D02*
X1230157Y08205D01*
X09349Y08452D02*
X09368Y08471D01*
X0939328*
X0941401Y0843525D02*
Y0843954D01*
X09405Y0844855D02*
Y0845928D01*
X0941401Y0843525D02*
X0941869Y0843057D01*
X0942569D02*
X0944138Y0841488D01*
X0939328Y08471D02*
X09405Y0845928D01*
X0944138Y0839913D02*
Y0841488D01*
X0941869Y0843057D02*
X0942569D01*
X09405Y0844855D02*
X0941401Y0843954D01*
X08495Y0848874D02*
X0856874D01*
X0844248Y0856748D02*
X08495D01*
X08425Y0855D02*
X0844248Y0856748D01*
X0856874Y0848874D02*
X0857Y0849D01*
X0776671Y0667794D02*
X0781294D01*
X0776671Y0661889D02*
X0780589D01*
X07884Y06697*
X09215Y0666528D02*
X0923472Y06685D01*
X0925128*
X1243773Y084D02*
X1244984Y0838789D01*
Y0833604D02*
Y0838789D01*
X0881916Y0865987D02*
X08825Y0866571D01*
X0881916Y0864916D02*
Y0865987D01*
X0879Y0862D02*
X0881916Y0864916D01*
X0958Y06715D02*
X095817D01*
X0975181Y0650074D02*
X0976607Y06515D01*
X0964162Y0650074D02*
X0975181D01*
X08949Y07625D02*
X0897085Y0760315D01*
X0889211Y0730889D02*
Y0736275D01*
X09243Y06665D02*
X0924978Y0665822D01*
X0755661Y0632361D02*
X0760727D01*
X07745Y0709225D02*
X0774592Y0709133D01*
X0941267Y0639126D02*
X0942131Y0638263D01*
X0885274Y0732374D02*
Y0736275D01*
X0842Y07307D02*
Y0732628D01*
X0924978Y0665822D02*
X0948218D01*
X09395Y0636726D02*
X0939933D01*
X0948205Y0687488D02*
X0948218Y0687475D01*
X08832Y07267D02*
Y07303D01*
X0760727Y0709133D02*
Y0712227D01*
X0937326Y0634326D02*
X0948218D01*
X09289Y06975D02*
X0936864D01*
X0777162Y0631138D02*
X07782Y06301D01*
X0774592Y0709133D02*
X0776671D01*
X0937126Y0639126D02*
X0941267D01*
X095376Y064426D02*
X0954Y06445D01*
X0865589Y0729511D02*
X08656Y07295D01*
X08911Y0729D02*
X08933D01*
X084198Y0732648D02*
X0842Y0732628D01*
X089109Y075213D02*
X0891179Y0752219D01*
X0939933Y0636726D02*
X0940365Y0636294D01*
X0964254Y0648197D02*
X0982197D01*
X0889211Y0730889D02*
X08911Y0729D01*
X084198Y0732648D02*
Y0736262D01*
X0940365Y0636294D02*
X0948218D01*
X094831Y064426D02*
X095376D01*
X08794Y07311D02*
Y0736243D01*
X0865589Y0729511D02*
Y0736275D01*
X089109Y0743211D02*
Y075213D01*
X0839998Y0731802D02*
X084Y07318D01*
X0776663Y0654007D02*
X0776671Y0654015D01*
X0777162Y0631138D02*
Y0632269D01*
X0787164Y0707164D02*
X07875Y07075D01*
X077707Y0632361D02*
X0777162Y0632269D01*
X0776671Y0707164D02*
X0787164D01*
X08832Y07303D02*
X0885274Y0732374D01*
X084Y07287D02*
X0842Y07307D01*
X0760727Y0712227D02*
X0761Y07125D01*
X0937Y0634D02*
X0937326Y0634326D01*
X0871494Y0730123D02*
Y0736275D01*
X0839998Y0731802D02*
Y0736275D01*
X0843935Y0728981D02*
Y0736275D01*
X0897085Y0752219D02*
Y0760315D01*
X0942941Y0687488D02*
X0948205D01*
X086362Y0730348D02*
Y0736275D01*
X0771007Y0654007D02*
X0776663D01*
X089109Y0743211D02*
X08911Y07432D01*
X0964162Y0657948D02*
X097692D01*
X0977868Y0657D02*
X09885D01*
X0776671Y0632361D02*
X077707D01*
X08466Y07295D02*
Y0729673D01*
X08885Y07435D02*
Y0746894D01*
X0843935Y0728981D02*
X08441Y0728817D01*
X0845904Y0730369D02*
X08466Y0729673D01*
X08885Y0746894D02*
X0889211Y0747605D01*
X0937Y0639D02*
X0937126Y0639126D01*
X0964162Y0648105D02*
X0964254Y0648197D01*
X0895116Y0731584D02*
X08976Y07291D01*
X0841967Y0736275D02*
X084198Y0736262D01*
X097692Y0657948D02*
X0977868Y0657D01*
X0948218Y0644168D02*
X094831Y064426D01*
X0879368Y0736275D02*
X08794Y0736243D01*
X08636Y07278D02*
Y0730328D01*
X0982197Y0648197D02*
X09825Y06485D01*
X0895116Y0731584D02*
Y0736275D01*
X0755836Y0707164D02*
X0760727D01*
X08636Y0730328D02*
X086362Y0730348D01*
X0771Y0654D02*
X0771007Y0654007D01*
X0871494Y0730123D02*
X08717Y0729916D01*
X094492Y0689444D02*
X0948218D01*
X08717Y07297D02*
Y0729916D01*
X0936864Y06975D02*
X094492Y0689444D01*
X0845904Y0730369D02*
Y0736275D01*
X0889211Y0747605D02*
Y0752219D01*
X07556Y06323D02*
X0755661Y0632361D01*
X07745Y0709225D02*
Y0713D01*
X0925838Y066779D02*
X0948218D01*
X0942131Y0638263D02*
X0948218D01*
X08441Y07286D02*
Y0728817D01*
X0976607Y06515D02*
X09855D01*
X0925128Y06685D02*
X0925838Y066779D01*
X0952126Y0800028D02*
X0953793Y0798361D01*
Y0797907D02*
Y0798361D01*
Y0797907D02*
X0957Y07947D01*
X0692279Y0591D02*
X06995D01*
X0692279Y06435D02*
X06998D01*
X06999Y06434*
X0692279Y0696D02*
X07D01*
X0692279Y07485D02*
X07011D01*
X07788Y05359D02*
X08056D01*
X0829294Y0559594D02*
X08455D01*
X08056Y05359D02*
X0829294Y0559594D01*
X08455D02*
X0905D01*
X0952126Y0799831D02*
Y0800028D01*
X0946Y0865784D02*
Y0866571D01*
X0945416Y0865199D02*
X0946Y0865784D01*
X0944628Y0865199D02*
X0945416D01*
X0943735Y0864306D02*
X0944628Y0865199D01*
X0941806Y0864306D02*
X0943735D01*
X09415Y0864D02*
X0941806Y0864306D01*
X092325Y0866321D02*
X09235Y0866571D01*
X092325Y086025D02*
Y0866321D01*
X0923Y086D02*
X092325Y086025D01*
X0952Y08485D02*
X095211Y084839D01*
X0867071Y0866571D02*
X0871D01*
X0867Y08665D02*
X0867071Y0866571D01*
X0969173Y0875673D02*
Y0879D01*
X0969Y08755D02*
X0969173Y0875673D01*
Y0884173D02*
Y08865D01*
X0969Y0884D02*
X0969173Y0884173D01*
X1017Y06605D02*
D01*
X0971445Y0667845D02*
X09715Y06679D01*
X1233Y08155D02*
X1233142Y0815642D01*
X1237848*
X1069716Y09125D02*
X107023Y0911987D01*
X1074487*
X1021216Y0852D02*
X1029146D01*
X1125716Y0909284D02*
Y0913D01*
X0976272Y086875D02*
X0978503D01*
X0986161Y0876221D02*
Y0902764D01*
X0978503Y086875D02*
X0978917Y0869164D01*
X0979104*
X0986161Y0876221*
X0995497Y086875D02*
X0997728D01*
X0989311Y0874749D02*
Y0902764D01*
X0995083Y0869164D02*
X0995497Y086875D01*
X0994896Y0869164D02*
X0995083D01*
X0989311Y0874749D02*
X0994896Y0869164D01*
X0899079Y08705D02*
X0902516Y0867063D01*
X09035*
X1200051Y0734283D02*
X1203113Y0737346D01*
X11995Y0734283D02*
X1200051D01*
X1203113Y0737346D02*
X1204653D01*
X12055Y0738193*
X1245Y0815396D02*
X1245092Y0815488D01*
Y0816856*
X1245964Y0817728*
X1247942*
X1243016Y0815396D02*
Y0819484D01*
X1243Y08195D02*
X1243016Y0819484D01*
X1234491Y0833508D02*
X123464Y0833358D01*
X1237848*
X1241047Y0833604D02*
X1241139Y0833512D01*
Y0831861D02*
Y0833512D01*
Y0831861D02*
X12435Y08295D01*
X124Y08375D02*
X12415D01*
X1243016Y0835984*
Y0833604D02*
Y0835984D01*
X1246953Y0842953D02*
X1247Y0843D01*
X125Y0846D02*
X1250152Y0845848D01*
Y0833358D02*
Y0845848D01*
X1246953Y0833604D02*
Y0842953D01*
X0882992Y0867063D02*
X08935D01*
X08825Y0866571D02*
X0882992Y0867063D01*
X09035Y0874937D02*
Y08955D01*
X09135Y0867063D02*
X0923008D01*
X09235Y0866571*
X0934Y0867063D02*
X0945508D01*
X0946Y0866571*
X0958Y0873146D02*
Y0873441D01*
X0959273Y0874714*
X0961442*
X0965728Y0879*
X0965827*
X0965728Y08865D02*
X0965827D01*
X0960874Y0891354D02*
X0965728Y08865D01*
X0958Y0891354D02*
X0960874D01*
X0969173Y08865D02*
X0969298Y0886375D01*
X0976147*
X0976272Y088625*
X0969173Y0879D02*
X0969298Y0878875D01*
X0976147*
X0976272Y087875*
X0658496Y0591D02*
X0692279D01*
X0619D02*
X0658496D01*
Y06435D02*
X0692279D01*
X0619D02*
X0658496D01*
Y0696D02*
X0692279D01*
X0619D02*
X0658496D01*
Y07485D02*
X0692279D01*
X0619D02*
X0658496D01*
X1293Y0689307D02*
X1299476D01*
X13Y0688784*
X1282244Y06935D02*
X1292193D01*
X1293Y0692693*
X1282244Y07035D02*
X1282628D01*
X128335Y0704222*
Y071*
X1274Y0703988D02*
Y0709283D01*
Y0703988D02*
X1279488Y06985D01*
X1282244*
X1247177Y069585D02*
X1251D01*
X1235921Y0684594D02*
X1247177Y069585D01*
X1231Y0684594D02*
X1235921D01*
X1253252Y06935D02*
X1262756D01*
X1251Y0695752D02*
X1253252Y06935D01*
X1251Y0695752D02*
Y069585D01*
X125235Y07035D02*
X1262756D01*
X1251Y070215D02*
X125235Y07035D01*
X12055Y0734807D02*
X1205807Y07345D01*
X1214756*
X121465Y07175D02*
Y0724394D01*
X1214756Y07245*
X1234244D02*
X124585D01*
X1246Y072435*
X1250236Y0807693D02*
X12575D01*
X1250043Y08075D02*
X1250236Y0807693D01*
X1250043Y08075D02*
Y080809D01*
X124507Y0813064D02*
X1250043Y080809D01*
X124507Y0813064D02*
Y0815326D01*
X1245Y0815396D02*
X124507Y0815326D01*
X0703833Y0910304D02*
Y0919646D01*
X0703246Y0909717D02*
X0703833Y0910304D01*
X0724D02*
Y0919646D01*
X0723413Y0909717D02*
X0724Y0910304D01*
G54D14*
X0866451Y0821421D02*
X0877067D01*
X0834093Y0789063D02*
X0866451Y0821421D01*
X0834093Y0752219D02*
Y0789063D01*
X0786343Y0927409D02*
X0786934Y0928D01*
X0961583Y0573D02*
X0964957D01*
X09594Y0570817D02*
X0961583Y0573D01*
X09594Y05686D02*
Y0570817D01*
X1242957Y0803043D02*
Y08075D01*
Y0803043D02*
X12447Y08013D01*
X1260993Y0804307D02*
X12617Y08036D01*
X12575Y0804307D02*
X1260993D01*
X0789817Y0913317D02*
X07924D01*
X078685Y091035D02*
X0789817Y0913317D01*
X0783628Y091035D02*
X078685D01*
X07924Y0913317D02*
Y09261D01*
X07905Y0928D02*
X07924Y09261D01*
X0786934Y0928D02*
X07905D01*
X0786343Y0924843D02*
Y0927409D01*
X07844Y09229D02*
X0786343Y0924843D01*
X07678Y09229D02*
X07844D01*
X076545Y092525D02*
X07678Y09229D01*
X076545Y092525D02*
Y09277D01*
X0954708Y0705192D02*
X09562Y07037D01*
X0948218Y0705192D02*
X0954708D01*
X0954023Y0703223D02*
X09545Y07037D01*
X0948218Y0703223D02*
X0954023D01*
X09585Y07037D02*
X0958977Y0703223D01*
X0964162*
X095524Y070716D02*
X09562Y07062D01*
X095716Y070716*
X0994152Y0660348D02*
X0996Y06585D01*
Y06556D02*
Y06585D01*
X0991572Y0660348D02*
X0994152D01*
X09985Y06555D02*
Y06593D01*
X0995452Y0662348D02*
X09985Y06593D01*
X0990166Y0662348D02*
X0995452D01*
X1002385Y0655115D02*
Y0657915D01*
X0995952Y0664348D02*
X1002385Y0657915D01*
X0990166Y0664348D02*
X0995952D01*
X0942585Y0661885D02*
X0948218D01*
X09404Y06597D02*
X0942585Y0661885D01*
X09404Y06577D02*
Y06597D01*
X0946784Y07801D02*
X09475Y0780817D01*
Y0789628*
X07779Y0929357D02*
Y09331D01*
Y0929357D02*
X0779257Y0928D01*
X0960015Y0661885D02*
X0964162D01*
X09581Y06638D02*
X0960015Y0661885D01*
X09581Y06638D02*
Y06666D01*
X08774Y0752219D02*
Y07572D01*
X077121Y069929D02*
X0776671D01*
X07712Y06993D02*
X077121Y069929D01*
X0888727Y0838173D02*
X08925D01*
X08887Y08382D02*
X0888727Y0838173D01*
X0849842Y0588281D02*
Y0593542D01*
X08504Y05941D02*
X08505D01*
X0849842Y0593542D02*
X08504Y05941D01*
X086559Y0604225D02*
Y060959D01*
X08656Y06096*
X0851809Y0752219D02*
Y0792809D01*
X0874481Y0815481*
X0877032*
X0976272Y087625D02*
X0981588D01*
X0981938Y08766*
X09821*
X0828187Y0752219D02*
Y0755787D01*
X08314Y0759*
X0760727Y0679605D02*
X0760732Y06796D01*
X07662*
X0877401Y0604225D02*
Y0609799D01*
X08774Y06098D02*
X0877401Y0609799D01*
X09335Y0922508D02*
X0938508D01*
X09386Y09226*
X10263Y0808393D02*
X10265Y0808193D01*
X10263Y0808393D02*
Y08139D01*
X094821Y0671735D02*
X0948218Y0671727D01*
X0945363Y0671735D02*
X094821D01*
X0945339Y0671759D02*
X0945363Y0671735D01*
X09401Y0671759D02*
X0945339D01*
X077052Y065992D02*
X0776671D01*
X07705Y06599D02*
X077052Y065992D01*
X0872684Y0817484D02*
X0877067D01*
X08716Y08164D02*
X0872684Y0817484D01*
X0904638Y08159D02*
X09048D01*
X0904253Y0815516D02*
X0904638Y08159D01*
X0897933Y0815516D02*
X0904253D01*
X0813Y0870193D02*
Y08742D01*
X0847872Y0736275D02*
Y0741672D01*
X08479Y07417*
X0839999Y0604225D02*
Y0609199D01*
X08401Y06093*
X1012Y0852D02*
X1015784D01*
X0897933Y0819453D02*
X0901553D01*
X09034Y08213*
X0903472*
X0903536Y0821364*
X1019957Y0813957D02*
Y0825D01*
X10199Y08139D02*
X1019957Y0813957D01*
X1020015Y0813385D02*
X1021Y08124D01*
X1020015Y0813385D02*
Y0813785D01*
X10199Y08139D02*
X1020015Y0813785D01*
X1021Y0808193D02*
Y08124D01*
X0958904Y0652042D02*
X0964162D01*
X0958662Y06518D02*
X0958904Y0652042D01*
X09585Y06518D02*
X0958662D01*
X0867557Y0752219D02*
Y0757157D01*
X08676Y07572*
X0760727Y0640235D02*
X0766135D01*
X07662Y06403*
X10155Y0808193D02*
Y08121D01*
X1014415Y0813185D02*
X10155Y08121D01*
X1014415Y0813185D02*
Y0813785D01*
X10143Y08139D02*
X1014415Y0813785D01*
X10055Y07726D02*
Y0778457D01*
X0830157Y0588281D02*
Y0593757D01*
X08302Y05938*
X0887242Y0731142D02*
Y0736275D01*
X08862Y07301D02*
X0887242Y0731142D01*
X0760727Y0689448D02*
X0766548D01*
X07666Y06895*
X071472Y0696D02*
Y0696077D01*
X0719043Y07004*
X07239*
X0771237Y0669763D02*
X0776671D01*
X07712Y06698D02*
X0771237Y0669763D01*
X088Y07916D02*
Y0794327D01*
X08807Y07907D02*
Y07909D01*
X088Y07916D02*
X08807Y07909D01*
X0889Y0794327D02*
X0889267Y079406D01*
Y0792133D02*
Y079406D01*
Y0792133D02*
X08907Y07907D01*
X1005906Y0668356D02*
X1011394D01*
X1012038Y0669D02*
X10122D01*
X1011394Y0668356D02*
X1012038Y0669D01*
X0830157Y0604225D02*
Y0609395D01*
X08303Y0609538*
Y06097*
X1003Y080965D02*
X1004305Y0810954D01*
Y0812305*
X10059Y08139*
X083803Y0736275D02*
Y074013D01*
X08395Y07416*
X0964162Y06422D02*
X09723D01*
X0857715Y0752219D02*
Y0757285D01*
X08577Y07573D02*
X0857715Y0757285D01*
X0760727Y0650078D02*
X0760735Y0650086D01*
X0763582*
X0763596Y06501*
X07662*
X08961Y0838573D02*
X08965Y0838173D01*
X08961Y0838573D02*
Y08415D01*
X0762172Y091035D02*
X076615D01*
X07682Y09083*
X09633Y0564D02*
X0967307D01*
X08774Y0736275D02*
Y07433D01*
X0760727Y069929D02*
X076649D01*
X07665Y06993*
X0997728Y087875D02*
X100295D01*
X1003Y08788*
X1246716Y0823516D02*
X1250152D01*
X12467Y08235D02*
X1246716Y0823516D01*
X10325Y0808193D02*
Y08138D01*
X10324Y08139D02*
X10325Y08138D01*
X10445Y0808193D02*
Y08112D01*
X1046685Y0813385*
Y0813785*
X10468Y08139*
X0944804Y0652042D02*
X0948218D01*
X0943867Y0651104D02*
X0944804Y0652042D01*
X0943867Y0651067D02*
Y0651104D01*
X094Y06472D02*
X0943867Y0651067D01*
X094Y0646962D02*
Y06472D01*
X09397Y0646662D02*
X094Y0646962D01*
X09397Y06465D02*
Y0646662D01*
X0770765Y0640235D02*
X0776671D01*
X07707Y06403D02*
X0770765Y0640235D01*
X0770905Y0679605D02*
X0776671D01*
X07709Y06796D02*
X0770905Y0679605D01*
X0786343Y0927409D02*
Y0928D01*
X07592Y09277D02*
X076545D01*
X07548Y09233D02*
X07592Y09277D01*
X0917043Y0817D02*
X09188Y0818757D01*
Y08218*
X077175Y09277D02*
Y093295D01*
X07717Y0933D02*
X077175Y093295D01*
X0828187Y0732087D02*
Y0736275D01*
X08244Y07283D02*
X0828187Y0732087D01*
X0836061Y0752219D02*
Y0784961D01*
X0870518Y0819418*
X0877032*
X0877067Y0819453*
X0889212Y0588281D02*
Y0592512D01*
X08924Y05957*
X0847872Y0747272D02*
Y0752219D01*
X08466Y0746D02*
X0847872Y0747272D01*
X0760727Y065992D02*
X076608D01*
X07661Y06599*
X0889212Y0604225D02*
Y0609888D01*
X08892Y06099D02*
X0889212Y0609888D01*
X0990158Y0666356D02*
X0994756D01*
X09959Y06675*
X0995Y07729D02*
Y0778457D01*
Y07729D02*
X09951Y07728D01*
X0859684Y0588281D02*
Y0593584D01*
X08599Y05938D02*
X08601D01*
X0859684Y0593584D02*
X08599Y05938D01*
X0867557Y0731543D02*
Y0736275D01*
Y0731543D02*
X08676Y07315D01*
X0859684Y0604225D02*
Y0609484D01*
X08597Y06095*
X071472Y07485D02*
X07251D01*
X07252Y07486*
X0964162Y0671727D02*
X0970873D01*
X09709Y06717*
X0948218Y06422D02*
X0953338D01*
X0953838Y06417*
X0954*
X0887242Y0752219D02*
Y0756958D01*
X08872Y0757D02*
X0887242Y0756958D01*
X0770922Y0650078D02*
X0776671D01*
X07709Y06501D02*
X0770922Y0650078D01*
X0771248Y0689448D02*
X0776671D01*
X07712Y06894D02*
X0771248Y0689448D01*
X08845Y0794327D02*
X0885181Y0793646D01*
Y0792619D02*
Y0793646D01*
Y0792619D02*
X08875Y07903D01*
X1001556Y0674356D02*
X1005906D01*
X09987Y06715D02*
X1001556Y0674356D01*
X101Y0808193D02*
Y0813D01*
X1010385Y0813385*
Y0813785*
X10105Y08139*
X12595Y083315D02*
X126085Y08345D01*
X12639*
X0887908Y0922508D02*
X08935D01*
X08879Y09225D02*
X0887908Y0922508D01*
X0942447Y07892D02*
X0942874Y0789628D01*
X09361Y07892D02*
X0942447D01*
X083803Y0752219D02*
Y075643D01*
X08399Y07583*
X084*
X0760727Y0669763D02*
X0766063D01*
X07661Y06698*
X0883306Y0604225D02*
Y0609894D01*
X08833Y06099D02*
X0883306Y0609894D01*
X0941132Y068157D02*
X0948218D01*
X0940462Y06809D02*
X0941132Y068157D01*
X08755Y07908D02*
Y0794327D01*
X08753Y07906D02*
X08755Y07908D01*
X0822354Y0873807D02*
Y0873914D01*
X082294Y08745*
X082Y0872043D02*
X0820591D01*
X0822354Y0873807*
X082294Y08745D02*
X08249D01*
X0857715Y0732115D02*
Y0736275D01*
X08572Y07316D02*
X0857715Y0732115D01*
X0849842Y0604225D02*
Y0609342D01*
X08499Y06094*
X077545Y091285D02*
X0783628D01*
X0774Y09114D02*
X077545Y091285D01*
X0827154Y0917428D02*
Y0921154D01*
X08281Y09221*
X0990158Y0660356D02*
X0991564D01*
X0991572Y0660348*
X0990158Y0662356D02*
X0990166Y0662348D01*
X0990158Y0664356D02*
X0990166Y0664348D01*
X1002385Y0655115D02*
X10025Y0655D01*
X0976Y0820428D02*
Y0820507D01*
Y0820428D02*
X097676Y0819668D01*
X0976839*
X0985207Y08113*
X09871*
X09679Y083335D02*
X096915Y08346D01*
X09735*
X09684Y0812157D02*
X0968991D01*
X0970754Y0810393*
Y0809802D02*
Y0810393D01*
Y0809802D02*
X09708Y0809757D01*
Y08076D02*
Y0809757D01*
X09321Y0839687D02*
X0932327Y0839913D01*
X09321Y08305D02*
Y0839687D01*
X09562Y07037D02*
X09585D01*
X0957692Y0705192D02*
X0964162D01*
X09562Y07037D02*
X0957692Y0705192D01*
X095716Y070716D02*
X0959129Y0709129D01*
X095716Y070716D02*
X0964162D01*
X0959129Y0709129D02*
X0964162D01*
X09545Y07037D02*
X09562D01*
X0953271Y0709129D02*
X095524Y070716D01*
X0948218D02*
X095524D01*
X0948218Y0709129D02*
X0953271D01*
X11724Y0853557D02*
X1173957Y0852D01*
X11724Y0853557D02*
Y0856D01*
X1166693Y0852D02*
Y0854993D01*
X11667Y0855*
X0839999Y0588281D02*
Y0593599D01*
X08405Y05941*
X0964957Y0572743D02*
Y0573D01*
X0871495Y0604225D02*
Y0609695D01*
X08715Y06097*
X1261957Y0637657D02*
Y06425D01*
X12619Y06376D02*
X1261957Y0637657D01*
X12539Y06535D02*
X1261957D01*
X12594Y06615D02*
X1263307D01*
X12593Y06616D02*
X12594Y06615D01*
Y06675D02*
X1263307D01*
X12593Y06676D02*
X12594Y06675D01*
Y06725D02*
X1263307D01*
X12593Y06726D02*
X12594Y06725D01*
X12593Y0678D02*
X1263307D01*
X12592Y06781D02*
X12593Y0678D01*
X1271784Y0682D02*
Y0682283D01*
X1270866Y06832D02*
X1271784Y0682283D01*
X12676Y06832D02*
X1270866D01*
X1262756Y06885D02*
X1269D01*
X13Y0694216D02*
X1300566Y0694783D01*
X1302883*
X13042Y06961*
X128965Y071D02*
X12939D01*
X1294Y07099*
X1264043Y0718D02*
X1265Y0717043D01*
X12598Y0718D02*
X1264043D01*
X12325Y0711457D02*
X1238557D01*
X12386Y07115*
X12039Y07175D02*
X120835D01*
X11995Y0739716D02*
Y07438D01*
X12265Y07395D02*
X1234244D01*
X1235717Y07455D02*
X1235917Y07457D01*
X12389*
X1235193Y07505D02*
X12388D01*
X1235193Y0756D02*
X12387D01*
X1235193Y07615D02*
X12387D01*
X12388Y07614*
X1235193Y0766D02*
X12388D01*
X12389Y07661*
X1094507Y09207D02*
X1094807Y0921D01*
X10901Y09207D02*
X1094507D01*
X10378Y0921D02*
X1042307D01*
X09769Y09027D02*
X0976964Y0902764D01*
X09768Y09027D02*
X09769D01*
X0976964Y0902764D02*
X0979862D01*
X1009479Y0884565D02*
X10095Y0884543D01*
X1009479Y0884565D02*
Y0887721D01*
X10076Y08896D02*
X1009479Y0887721D01*
X10185Y088415D02*
Y08888D01*
X10385Y0808193D02*
Y0808272D01*
X103926Y0809031*
X1039339*
X10422Y0811893*
Y08139*
X09091Y07916D02*
X09125Y0795D01*
X0909Y07916D02*
X09091D01*
X09125Y0795D02*
Y0802457D01*
X09023Y07972D02*
X09045Y07994D01*
Y080335*
X0898854Y0790686D02*
X089944Y07901D01*
X08965Y0792457D02*
X0897091D01*
X0898854Y0790686D02*
Y0790693D01*
X089944Y07901D02*
X09009D01*
X0897091Y0792457D02*
X0898854Y0790693D01*
X0885059Y0875429D02*
Y0878859D01*
X08851Y08789*
X0873559Y0874642D02*
Y0875429D01*
X0873075Y0874158D02*
X0873559Y0874642D01*
X0872287Y0874158D02*
X0873075D01*
X08715Y087337D02*
X0872287Y0874158D01*
X08715Y08733D02*
Y087337D01*
X0948559Y0870141D02*
X09522Y08665D01*
Y08664D02*
Y08665D01*
X0948559Y0870141D02*
Y0875429D01*
X0926059D02*
Y0878841D01*
X0926Y08789D02*
X0926059Y0878841D01*
X071472Y06435D02*
X071882Y06476D01*
X07233*
X071472Y0591D02*
X0718321Y05946D01*
X07247*
X06645Y05794D02*
Y0585193D01*
Y0596807D02*
Y06031D01*
X06646Y06032*
X06645Y06318D02*
Y0637693D01*
Y0649307D02*
Y06554D01*
X06644Y06555D02*
X06645Y06554D01*
Y06843D02*
Y0690193D01*
Y0701807D02*
Y07077D01*
Y07369D02*
Y0742693D01*
Y0754307D02*
Y0759695D01*
X0664412Y0759783D02*
X06645Y0759695D01*
G54D18*
X094817Y0640183D02*
X0948218Y0640231D01*
X0776671Y0701259D02*
X0776697Y0701233D01*
X0776671Y0703227D02*
X0776677Y0703233D01*
X0939744Y0641526D02*
X0942202D01*
X0943497Y0640231*
X0948218*
G54D22*
X08409Y0513699D02*
D01*
X0840907Y0513482*
X084093Y0513266*
X0840967Y0513052*
X084102Y0512841*
X0841087Y0512635*
X0841168Y0512434*
X0841264Y0512238*
X0841372Y051205*
X0841493Y051187*
X0841627Y0511699*
X0841772Y0511538*
X0841811Y05115*
X08566Y0513815D02*
D01*
X0856607Y0513586*
X0856631Y0513359*
X0856671Y0513134*
X0856726Y0512912*
X0856797Y0512695*
X0856883Y0512483*
X0856983Y0512277*
X0857097Y051208*
X0857225Y051189*
X0857365Y051171*
X0857518Y051154*
X0857559Y05115*
X0841961Y0528261D02*
D01*
X0841788Y0528076*
X0841629Y0527879*
X0841484Y0527672*
X0841354Y0527455*
X0841239Y052723*
X084114Y0526997*
X0841058Y0526758*
X0840993Y0526514*
X0840944Y0526266*
X0840913Y0526015*
X08409Y0525763*
X08409Y05257*
X08763Y0513779D02*
D01*
X0876307Y0513554*
X0876331Y051333*
X087637Y0513108*
X0876424Y051289*
X0876494Y0512676*
X0876578Y0512468*
X0876677Y0512265*
X0876789Y0512071*
X0876915Y0511884*
X0877054Y0511707*
X0877204Y051154*
X0877244Y05115*
X08603Y0514387D02*
D01*
X0860309Y0514102*
X0860339Y0513818*
X0860389Y0513538*
X0860458Y0513261*
X0860546Y051299*
X0860652Y0512726*
X0860777Y051247*
X086092Y0512223*
X0861079Y0511987*
X0861255Y0511762*
X0861445Y051155*
X0861496Y05115*
X08398Y05285D02*
D01*
X0839486Y0528164*
X0839198Y0527807*
X0838934Y0527431*
X0838698Y0527038*
X083849Y0526629*
X083831Y0526206*
X0838161Y0525772*
X0838042Y0525329*
X0837954Y0524878*
X0837898Y0524423*
X0837874Y0523964*
X0837874Y052385*
X08603Y0526869D02*
D01*
X0860293Y0527059*
X0860273Y0527249*
X086024Y0527436*
X0860194Y0527621*
X0860135Y0527803*
X0860063Y0527979*
X085998Y0528151*
X0859885Y0528316*
X0859778Y0528474*
X0859661Y0528624*
X0859533Y0528766*
X08595Y05288*
X08772Y0511606D02*
D01*
X08772Y0511595*
X0877201Y0511585*
X0877203Y0511574*
X0877205Y0511564*
X0877209Y0511554*
X0877212Y0511544*
X0877217Y0511535*
X0877222Y0511526*
X0877228Y0511517*
X0877235Y0511509*
X0877242Y0511501*
X0877244Y05115*
X08694Y05952D02*
D01*
X08691Y0594878*
X0868824Y0594537*
X0868572Y0594178*
X0868346Y0593801*
X0868147Y059341*
X0867975Y0593006*
X0867832Y0592591*
X0867719Y0592167*
X0867635Y0591736*
X0867581Y0591301*
X0867558Y0590862*
X0867558Y0590753*
X0888284Y0583251D02*
D01*
X0888249Y0583247*
X0888214Y058324*
X0888181Y0583231*
X0888147Y058322*
X0888115Y0583207*
X08881Y05832*
X0887243Y0585269D02*
D01*
X088725Y0585064*
X0887271Y0584861*
X0887306Y058466*
X0887356Y0584462*
X0887419Y0584268*
X0887495Y0584078*
X0887585Y0583895*
X0887687Y0583718*
X0887801Y0583549*
X0887927Y0583388*
X0888064Y0583236*
X08881Y05832*
X0885275Y0588281D02*
D01*
X0885262Y0588267*
X0885251Y0588254*
X0885241Y0588239*
X0885232Y0588224*
X0885224Y0588208*
X0885217Y0588191*
X0885211Y0588174*
X0885206Y0588157*
X0885203Y058814*
X0885201Y0588122*
X08852Y0588104*
Y05881*
X08622Y05978D02*
D01*
X086243Y0598047*
X0862644Y059831*
X0862838Y0598588*
X0863012Y0598878*
X0863166Y059918*
X0863298Y0599492*
X0863409Y0599812*
X0863496Y0600139*
X0863561Y0600471*
X0863602Y0600808*
X086362Y0601146*
X0863621Y0601231*
X0875432Y0600736D02*
D01*
X0875441Y0600474*
X0875468Y0600213*
X0875514Y0599955*
X0875577Y05997*
X0875658Y0599451*
X0875756Y0599208*
X0875871Y0598973*
X0876002Y0598746*
X0876149Y0598528*
X087631Y0598322*
X0876485Y0598127*
X0876532Y0598081*
X08676Y0604124D02*
D01*
X0867599Y0604133*
X0867598Y0604143*
X0867596Y0604153*
X0867594Y0604163*
X0867591Y0604172*
X0867587Y0604182*
X0867583Y0604191*
X0867578Y0604199*
X0867572Y0604208*
X0867566Y0604215*
X0867559Y0604223*
X0867558Y0604225*
X0869953Y0591023D02*
D01*
Y0591024*
Y0591025*
Y0591027*
Y0591028*
Y059103*
X0869928Y0590754D02*
D01*
X0869937Y0590787*
X0869945Y0590821*
X086995Y0590856*
X0869953Y0590891*
X0869953Y0590915*
X0881338Y0581281D02*
D01*
X0881345Y0581075*
X0881366Y0580871*
X0881402Y0580669*
X0881452Y0580469*
X0881515Y0580274*
X0881592Y0580083*
X0881682Y0579899*
X0881785Y0579721*
X08819Y0579551*
X0882026Y0579389*
X0882163Y0579236*
X08822Y05792*
X08612Y05842D02*
D01*
X0861273Y0584278*
X0861341Y0584362*
X0861403Y0584451*
X0861459Y0584543*
X0861508Y058464*
X086155Y0584739*
X0861585Y0584841*
X0861613Y0584945*
X0861634Y0585051*
X0861647Y0585159*
X0861652Y0585266*
X0861653Y0585294*
X08582Y05817D02*
D01*
X0858284Y0581702*
X0858367Y0581711*
X085845Y0581726*
X0858532Y0581746*
X0858612Y0581772*
X085869Y0581804*
X0858766Y0581841*
X0858839Y0581883*
X0858909Y058193*
X0858975Y0581982*
X0859038Y0582038*
X0859054Y0582054*
X0871822Y0593822D02*
D01*
X0871448Y0593421*
X0871104Y0592996*
X0870791Y0592548*
X0870728Y059245*
X087053Y0592269D02*
D01*
X0870465Y0592233*
X0870414Y0592201*
X087053Y0592269D02*
D01*
X087056Y0592285*
X0870589Y0592304*
X0870617Y0592325*
X0870644Y0592348*
X0870668Y0592372*
X0870691Y0592399*
X0870713Y0592426*
X0870728Y059245*
X0879369Y0599323D02*
D01*
X0879374Y0599172*
X0879389Y0599023*
X0879416Y0598875*
X0879452Y0598729*
X0879498Y0598586*
X0879555Y0598446*
X0879621Y0598311*
X0879696Y0598181*
X087978Y0598056*
X0879872Y0597938*
X0879973Y0597826*
X088Y05978*
X0882629Y0599071D02*
D01*
X0882641Y0599059*
X0882654Y0599048*
X0882668Y0599039*
X0882682Y059903*
X0882697Y0599022*
X0882713Y0599016*
X0882729Y059901*
X0882745Y0599006*
X0882762Y0599003*
X0882778Y0599001*
X0882795Y0599*
X08828Y0599*
X08616Y05817D02*
D01*
X0861928Y0582052*
X0862231Y0582426*
X0862507Y0582821*
X0862755Y0583233*
X0862974Y0583662*
X0863162Y0584106*
X0863319Y0584561*
X0863444Y0585026*
X0863535Y0585499*
X0863594Y0585977*
X0863619Y0586458*
X0863621Y0586579*
X0870411Y0592199D02*
D01*
X0870351Y0592155*
X0870296Y0592108*
X0870243Y0592056*
X0870194Y0592002*
X087015Y0591944*
X0870109Y0591883*
X0870073Y0591819*
X0870041Y0591753*
X0870014Y0591685*
X0869992Y0591615*
X0869974Y0591544*
X0869962Y0591472*
X0869955Y0591399*
X0869953Y0591332*
X0870414Y0592201D02*
D01*
X0870413Y05922*
X0870412Y05922*
X0870412Y0592199*
X0870411Y0592199*
X0870411Y0592198*
Y0592199*
D01*
X0870351Y0592155*
X0870296Y0592108*
X0870243Y0592056*
X0870194Y0592002*
X087015Y0591944*
X0870109Y0591883*
X0870073Y0591819*
X0870041Y0591753*
X0870014Y0591685*
X0869992Y0591615*
X0869974Y0591544*
X0869962Y0591472*
X0869955Y0591399*
X0869953Y0591332*
X086993Y0590875D02*
D01*
X0869939Y0590908*
X0869946Y0590942*
X0869951Y0590977*
X0869953Y0591012*
X0869953Y0591023*
X086993Y0590875D02*
D01*
X0869768Y0590299*
X0869648Y0589714*
X0869568Y0589122*
X0869531Y0588525*
X0869527Y0588281*
X0869927Y0590754D02*
D01*
X0869772Y0590229*
X0869655Y0589695*
X0869575Y0589153*
X0869533Y0588608*
X0869527Y0588281*
X08692Y05985D02*
D01*
X0869253Y0598556*
X0869302Y0598617*
X0869346Y0598681*
X0869386Y0598748*
X0869422Y0598817*
X0869452Y0598889*
X0869478Y0598962*
X0869498Y0599037*
X0869513Y0599114*
X0869522Y0599191*
X0869526Y0599269*
X0869527Y059929*
X08658Y05985D02*
D01*
X0866085Y0598806*
X0866349Y0599131*
X0866589Y0599475*
X0866805Y0599834*
X0866995Y0600207*
X0867159Y0600593*
X0867295Y0600989*
X0867404Y0601393*
X0867484Y0601805*
X0867535Y060222*
X0867557Y0602639*
X0867558Y0602744*
X08783Y0579D02*
D01*
X0878473Y0579186*
X0878634Y0579384*
X087878Y0579593*
X0878911Y0579811*
X0879027Y0580038*
X0879126Y0580272*
X0879209Y0580513*
X0879275Y0580759*
X0879324Y058101*
X0879355Y0581262*
X0879368Y0581517*
X0879369Y0581581*
X0873525Y0604077D02*
D01*
X0873524Y0604091*
X0873522Y0604106*
X087352Y060412*
X0873516Y0604134*
X0873512Y0604148*
X0873506Y0604162*
X08735Y0604175*
X0873493Y0604187*
X0873485Y0604199*
X0873476Y0604211*
X0873466Y0604222*
X0873464Y0604225*
X08602Y05991D02*
D01*
X0860436Y0599353*
X0860654Y0599622*
X0860852Y0599906*
X0861031Y0600202*
X0861188Y0600511*
X0861323Y060083*
X0861436Y0601157*
X0861525Y0601492*
X0861591Y0601831*
X0861634Y0602175*
X0861652Y0602521*
X0861653Y0602608*
X0881338Y0601722D02*
D01*
X0881346Y0601492*
X0881369Y0601264*
X0881409Y0601039*
X0881465Y0600816*
X0881536Y0600598*
X0881622Y0600385*
X0881722Y0600179*
X0881837Y0599981*
X0881965Y0599791*
X0882106Y059961*
X0882259Y059944*
X08823Y05994*
X0875432Y058501D02*
D01*
X0875441Y0584738*
X0875469Y0584469*
X0875516Y0584202*
X0875582Y0583939*
X0875666Y0583681*
X0875767Y0583429*
X0875886Y0583186*
X0876022Y0582951*
X0876173Y0582726*
X087634Y0582512*
X0876522Y0582311*
X087657Y0582263*
X0873464Y0588281D02*
D01*
X0873453Y0588269*
X0873443Y0588257*
X0873435Y0588245*
X0873427Y0588232*
X087342Y0588218*
X0873414Y0588204*
X0873409Y058819*
X0873405Y0588175*
X0873402Y058816*
X08734Y0588145*
X0873399Y0588129*
X08734Y0588127*
X0841961Y0528261D02*
X08422Y05285D01*
X0889055Y05115D02*
X08898Y0512245D01*
X087621Y0528247D02*
Y052879D01*
X08736Y0511793D02*
Y0529D01*
X08566Y0513815D02*
Y05289D01*
X0873307Y05115D02*
X08736Y0511793D01*
X0837874Y05115D02*
Y052385D01*
X0876Y0529D02*
X087621Y052879D01*
X08603Y0514387D02*
Y0526869D01*
X08922Y0512292D02*
Y05287D01*
X08409Y0513699D02*
Y05257D01*
X08898Y0512245D02*
Y05287D01*
X087621Y0528247D02*
X08763Y0528157D01*
X08731Y0511707D02*
X0873307Y05115D01*
X08763Y0513779D02*
Y0528157D01*
X08922Y0512292D02*
X0892992Y05115D01*
X0867558Y0588281D02*
Y0590753D01*
X0888284Y0583251D02*
X0888285D01*
X0887243Y0585269D02*
Y0588281D01*
X08852Y05824D02*
Y05881D01*
X0863621Y0601231D02*
Y0604225D01*
X0875432Y0600736D02*
Y0604225D01*
X08588Y05979D02*
X0859D01*
X0869953Y0591023D02*
Y059103D01*
X08734Y05827D02*
Y0588127D01*
X0869927Y0590754D02*
D01*
X0875432Y058501D02*
Y0588281D01*
X0879369Y0604225D02*
X08794Y0604194D01*
X087053Y0592269D02*
D01*
X0863621Y0586579D02*
Y0588281D01*
X08823Y05994D02*
X0882629Y0599071D01*
X0871822Y0593822D02*
X08727Y05947D01*
X0881338Y0601722D02*
Y0604225D01*
X0870728Y059245D02*
D01*
X0861653Y0585294D02*
Y0588281D01*
X0869953Y0590915D02*
Y0591023D01*
X0859Y05979D02*
X08602Y05991D01*
X0869953Y059103D02*
Y0591332D01*
X0861653Y0602608D02*
Y0604225D01*
X0859054Y0582054D02*
X08612Y05842D01*
X0873525Y0599177D02*
Y0604077D01*
X08828Y0599D02*
X0882941Y0599141D01*
X0867558Y0602744D02*
Y0604225D01*
X0869527Y059929D02*
Y0604225D01*
X0881338Y0581281D02*
Y0588281D01*
X0879369Y0581581D02*
Y0588281D01*
Y0599323D02*
Y0604225D01*
G54D24*
X1259535Y0813386D02*
X126378D01*
X12595Y081335D02*
X1259535Y0813386D01*
X124773Y08129D02*
X1254162D01*
X1246961Y0813669D02*
X124773Y08129D01*
X1246961Y0813669D02*
Y0814764D01*
X1254613Y081335D02*
X12595D01*
X1254162Y08129D02*
X1254613Y081335D01*
X1246953Y0814772D02*
X1246961Y0814764D01*
G54D26*
X128335Y071D03*
X128965D03*
X121465Y07175D03*
X120835D03*
X091215Y0825D03*
X090585D03*
X077175Y09277D03*
X076545D03*
G54D27*
X1208016Y0856D03*
X1202584D03*
X0952217Y07801D03*
X0946784D03*
X1015784Y0852D03*
X1021216D03*
X1283284Y0682D03*
X1288717D03*
X1271784D03*
X1277217D03*
X1230284Y07455D03*
X1235717D03*
X1010283Y08705D03*
X1015716D03*
X1069716Y0921D03*
X1064283D03*
X1125716D03*
X1120284D03*
X1069716Y09125D03*
X1064283D03*
X1120284Y0913D03*
X1125716D03*
G54D28*
X0818985Y09279D03*
X084556D03*
G54D29*
X0827154Y0917428D03*
X0829713D03*
X0832272D03*
X0834832D03*
X0837391D03*
G54D30*
X0842115Y0917762D03*
X082243D03*
G54D31*
X08368Y09279D03*
G54D32*
X082617Y09279D03*
G54D33*
X0979862Y0902764D03*
X0983012D03*
X0986161D03*
X0989311D03*
X0992461D03*
G54D34*
X0968642Y0924811D03*
Y0903158D03*
X1003681D03*
Y0924811D03*
G54D35*
X06645Y0585193D03*
Y0596807D03*
Y0701807D03*
Y0690193D03*
Y0754307D03*
Y0742693D03*
Y0637693D03*
Y0649307D03*
G54D36*
X0658496Y0591D03*
Y0696D03*
Y07485D03*
Y06435D03*
G54D37*
X0948559Y0875429D03*
X0943441D03*
X0946Y0866571D03*
X0885059Y0875429D03*
X0879941D03*
X08825Y0866571D03*
X0873559Y0875429D03*
X0868441D03*
X0871Y0866571D03*
X0926059Y0875429D03*
X0920941D03*
X09235Y0866571D03*
G54D38*
X0762172Y092035D03*
Y091785D03*
Y091535D03*
Y091285D03*
Y091035D03*
Y090785D03*
Y090535D03*
Y090285D03*
X0783628Y092035D03*
Y091785D03*
Y091535D03*
Y091285D03*
Y091035D03*
Y090785D03*
Y090535D03*
Y090285D03*
X0976272Y088625D03*
Y088375D03*
Y088125D03*
Y087875D03*
Y087625D03*
Y087375D03*
Y087125D03*
Y086875D03*
X0997728Y088625D03*
Y088375D03*
Y088125D03*
Y087875D03*
Y087625D03*
Y087375D03*
Y087125D03*
Y086875D03*
G54D39*
X1214756Y07245D03*
Y07295D03*
Y07345D03*
Y07395D03*
X1234244D03*
Y07345D03*
Y07295D03*
Y07245D03*
X1282244Y07035D03*
Y06985D03*
Y06935D03*
Y06885D03*
X1262756D03*
Y06935D03*
Y06985D03*
Y07035D03*
G54D40*
X1218815Y08705D03*
X1233185D03*
X1187815D03*
X1202185D03*
X1219315Y0857D03*
X1233685D03*
G54D41*
X1271673Y0829799D03*
X1293327D03*
Y0817201D03*
X1271673D03*
G54D42*
X0955949Y0838929D03*
G54D43*
X0938232Y0839913D03*
X0950043Y0821016D03*
X0932327D03*
Y0839913D03*
X0955949Y0821016D03*
X0950043Y0839913D03*
X0944138D03*
X0938232Y0821016D03*
X0944138D03*
G54D44*
X0951535Y0799962D03*
Y0795238D03*
X0943465D03*
Y0799962D03*
G54D45*
X09475Y0805572D03*
Y0789628D03*
G54D46*
X0952126Y0789628D03*
Y0805572D03*
X0942874Y0789628D03*
Y0805572D03*
G54D47*
X08935Y08955D03*
Y0922508D03*
X09035Y08955D03*
Y0922508D03*
X09135Y08955D03*
Y0922508D03*
X09235Y08955D03*
Y0922508D03*
X09335Y08955D03*
Y0922508D03*
G54D48*
X0934Y0874937D03*
Y0867063D03*
X08935Y0874937D03*
Y0867063D03*
X09035Y0874937D03*
Y0867063D03*
X09135Y0874937D03*
Y0867063D03*
G54D49*
X08755Y0797673D03*
Y0794327D03*
X08455Y0556248D03*
Y0559594D03*
X0905Y0556248D03*
Y0559594D03*
X0889Y0797673D03*
Y0794327D03*
X08845Y0797673D03*
Y0794327D03*
X088Y0797673D03*
Y0794327D03*
X08925Y0834827D03*
Y0838173D03*
X08965Y0834827D03*
Y0838173D03*
G54D50*
X08875Y08165D03*
G54D51*
X088061Y0826933D03*
X0882579D03*
X0884547D03*
X0886516D03*
X0888484D03*
X0890453D03*
X0892421D03*
X089439D03*
Y0806067D03*
X0892421D03*
X0890453D03*
X0888484D03*
X0886516D03*
X0884547D03*
X0882579D03*
X088061D03*
G54D52*
X0897933Y082339D03*
Y0821421D03*
Y0819453D03*
Y0817484D03*
Y0815516D03*
Y0813547D03*
Y0811579D03*
Y080961D03*
X0877067D03*
Y0811579D03*
Y0813547D03*
Y0815516D03*
Y0817484D03*
Y0819453D03*
Y0821421D03*
Y082339D03*
G54D53*
X0908661Y0514173D03*
X0786614D03*
X0782677D03*
X077874D03*
X0806299D03*
X0849606D03*
X0892913D03*
X0888976D03*
X0877165D03*
X0873228D03*
X0861417D03*
X085748D03*
X0841732D03*
X0837795D03*
X0814173D03*
X0810236D03*
X0829921D03*
X0900787D03*
X0794488D03*
X0798425D03*
X081811D03*
X089685D03*
X0885039D03*
X0869291D03*
X0865354D03*
X0802362D03*
X0790551D03*
X0881102D03*
X0833858D03*
X0845669D03*
X0853543D03*
G54D54*
X0904724Y0516123D03*
G54D55*
X1108193Y0921D03*
X1094807D03*
X1055693D03*
X1042307D03*
G54D56*
X1005906Y0678356D03*
X0990158D03*
X1005906Y0676356D03*
X0990158D03*
X1005906Y0674356D03*
X0990158D03*
X1005906Y0672356D03*
X0990158D03*
X1005906Y0670356D03*
X0990158D03*
X1005906Y0668356D03*
X0990158D03*
X1005906Y0666356D03*
X0990158D03*
X1005906Y0664356D03*
X0990158D03*
X1005906Y0662356D03*
X0990158D03*
Y0660356D03*
X1005906D03*
G54D57*
X1246953Y0815396D03*
X1245D03*
X1243016D03*
X1241047D03*
Y0833604D03*
X1243016D03*
X1244984D03*
X1246953D03*
G54D58*
X1250152Y0815642D03*
X1237848D03*
Y081761D03*
Y0819579D03*
Y0821547D03*
Y0823516D03*
Y0825484D03*
Y0827453D03*
Y0829421D03*
Y083139D03*
Y0833358D03*
X1250152D03*
Y083139D03*
Y0829421D03*
Y0827453D03*
Y0825484D03*
Y0823516D03*
Y0821547D03*
Y081761D03*
Y0819579D03*
G54D59*
X1014Y0784618D03*
Y0779382D03*
X09205Y0803882D03*
Y0809118D03*
X10425Y0784618D03*
Y0779382D03*
G54D60*
X1267Y0780594D03*
Y0742406D03*
X1231Y0646406D03*
Y0684594D03*
G54D61*
X1085Y082D03*
Y0879745D03*
G54D62*
X0692279Y0591D03*
X071472D03*
Y0696D03*
X0692279D03*
X071472Y07485D03*
X0692279D03*
Y06435D03*
X071472D03*
G54D63*
X0724Y0920146D03*
Y0925854D03*
X0958Y0891354D03*
Y0885646D03*
Y0873146D03*
Y0878854D03*
X06635Y0925854D03*
Y0920146D03*
X0683667Y0925854D03*
Y0920146D03*
X0703833D03*
Y0925854D03*
G54D64*
X1033Y0785543D03*
Y0778457D03*
X12325Y0718543D03*
Y0711457D03*
X1265Y0709957D03*
Y0717043D03*
X1224409Y0775984D03*
Y0783071D03*
X123622Y0775984D03*
Y0783071D03*
X10095Y0884543D03*
Y0877457D03*
X082Y0864957D03*
Y0872043D03*
X0863Y0861043D03*
Y0853957D03*
X09684Y0812157D03*
Y0819243D03*
X09125Y0802457D03*
Y0809543D03*
X08965Y0799543D03*
Y0792457D03*
X10055Y0785543D03*
Y0778457D03*
X0995Y0785543D03*
Y0778457D03*
X10225Y0785543D03*
Y0778457D03*
G54D65*
X1003Y080965D03*
Y080335D03*
X1246Y073065D03*
Y072435D03*
X1251Y070215D03*
Y069585D03*
X10185Y088415D03*
Y087785D03*
X09679Y083335D03*
Y082705D03*
X09045Y080335D03*
Y080965D03*
X12595Y083315D03*
Y082685D03*
Y081335D03*
Y081965D03*
G54D66*
X101Y0808193D03*
Y0804807D03*
X1293Y0692693D03*
Y0689307D03*
X12055Y0738193D03*
Y0734807D03*
X12575Y0807693D03*
Y0804307D03*
X0813Y0866807D03*
Y0870193D03*
X08715Y0859693D03*
Y0856307D03*
X0976Y0820507D03*
Y0823893D03*
X10445Y0808193D03*
Y0804807D03*
X10385Y0808193D03*
Y0804807D03*
X10325Y0808193D03*
Y0804807D03*
X10265Y0808193D03*
Y0804807D03*
X1021Y0808193D03*
Y0804807D03*
X10155Y0808193D03*
Y0804807D03*
G54D67*
X0901514Y0744247D03*
X0901515Y0596253D03*
X0815885D03*
X0815884Y0744247D03*
G54D68*
X0820314Y0604225D03*
Y0588281D03*
X0830157D03*
X0839999D03*
X0849842D03*
X0859684D03*
X086559D03*
X0871495D03*
X0877401D03*
X0883306D03*
X0889212D03*
X0830157Y0604225D03*
X0839999D03*
X0849842D03*
X0859684D03*
X086559D03*
X0871495D03*
X0877401D03*
X0883306D03*
X0889212D03*
X0895117Y0588281D03*
Y0604225D03*
X0897086D03*
Y0588281D03*
X0893149Y0604225D03*
Y0588281D03*
X089118Y0604225D03*
Y0588281D03*
X0887243Y0604225D03*
X0885275D03*
X085181D03*
X0853779D03*
X0832125D03*
X0834094D03*
X0822283D03*
X0824251D03*
X082622D03*
X0828188D03*
X0843936D03*
X0847873D03*
X0845905D03*
X0841968D03*
X0838031D03*
X0836062D03*
X0855747D03*
X082622Y0588281D03*
X0824251D03*
X0845905D03*
X0843936D03*
X0855747D03*
X0853779D03*
X085181D03*
X0847873D03*
X0838031D03*
X0828188D03*
X0832125D03*
X0834094D03*
X0836062D03*
X0841968D03*
X0822283D03*
X0863621Y0604225D03*
X0861653D03*
X0869527Y0588281D03*
X0867558D03*
X0881338D03*
X0879369D03*
X0875432Y0604225D03*
X0873464D03*
X0861653Y0588281D03*
X0863621D03*
X0857716Y0604225D03*
Y0588281D03*
X0869527Y0604225D03*
X0867558D03*
X0875432Y0588281D03*
X0873464D03*
X0887243D03*
X0885275D03*
X0881338Y0604225D03*
X0879369D03*
X0832124Y0752219D03*
X0830156D03*
X0826219Y0736275D03*
X0832124D03*
X0830156D03*
X082425D03*
X0895116Y0752219D03*
X0893148D03*
X0885274D03*
X0883305D03*
X0891179D03*
X0889211D03*
X0875431D03*
X0873463D03*
X0881337D03*
X0879368D03*
X0865589D03*
X086362D03*
X0871494D03*
X0869526D03*
X0855746D03*
X0861652D03*
X0853778D03*
X0859683D03*
X0845904D03*
X0843935D03*
X0851809D03*
X0849841D03*
X0836061D03*
X0834093D03*
X0841967D03*
X0839998D03*
X0826219D03*
X082425D03*
X0820313Y0736275D03*
X0822282D03*
Y0752219D03*
X0820313D03*
X0836061Y0736275D03*
X0834093D03*
X0841967D03*
X0839998D03*
X0845904D03*
X0843935D03*
X0851809D03*
X0849841D03*
X0855746D03*
X0853778D03*
X0861652D03*
X0859683D03*
X0865589D03*
X086362D03*
X0871494D03*
X0869526D03*
X0875431D03*
X0873463D03*
X0881337D03*
X0879368D03*
X0885274D03*
X0883305D03*
X0891179D03*
X0889211D03*
X0895116D03*
X0893148D03*
X0828187D03*
X083803D03*
X0847872D03*
X0857715D03*
X0867557D03*
X08774D03*
X0887242D03*
X0828187Y0752219D03*
X083803D03*
X0847872D03*
X0857715D03*
X0867557D03*
X08774D03*
X0887242D03*
X0897085Y0736275D03*
Y0752219D03*
G54D69*
X0760727Y0707164D03*
X0776671Y0654015D03*
Y0707164D03*
Y0709133D03*
X0760727D03*
Y069929D03*
Y0689448D03*
Y0679605D03*
Y0669763D03*
Y065992D03*
Y0650078D03*
Y0640235D03*
X0776671Y069929D03*
Y0689448D03*
Y0679605D03*
Y0669763D03*
Y065992D03*
Y0650078D03*
Y0640235D03*
Y0705196D03*
X0760727D03*
X0776671Y0652046D03*
X0760727Y0665826D03*
Y0671731D03*
X0776671Y0648109D03*
X0760727Y0632361D03*
X0776671Y0642204D03*
Y0632361D03*
Y0638267D03*
X0760727Y0677637D03*
Y0663857D03*
Y063433D03*
X0776671Y0636298D03*
X0760727Y0675668D03*
Y0642204D03*
Y0648109D03*
Y0638267D03*
Y0667794D03*
Y06737D03*
Y0661889D03*
Y0655983D03*
Y0654015D03*
Y0644172D03*
Y0657952D03*
X0776671Y063433D03*
X0760727Y0636298D03*
X0776671Y0644172D03*
X0760727Y0683542D03*
Y0681574D03*
Y0646141D03*
Y0652046D03*
X0776671Y0657952D03*
Y0655983D03*
X0760727Y0695353D03*
X0776671Y0671731D03*
Y0675668D03*
X0760727Y0701259D03*
X0776671Y0665826D03*
Y0681574D03*
Y0685511D03*
Y0693385D03*
X0760727Y0697322D03*
Y0687479D03*
X0776671Y0667794D03*
Y0646141D03*
Y0697322D03*
Y0701259D03*
X0760727Y0703227D03*
Y0691416D03*
Y0685511D03*
Y0693385D03*
X0776671Y0677637D03*
Y06737D03*
Y0695353D03*
Y0683542D03*
Y0691416D03*
Y0703227D03*
Y0687479D03*
Y0661889D03*
Y0663857D03*
X0964162Y0703223D03*
Y0705192D03*
Y070716D03*
Y0709129D03*
X0948218Y0703223D03*
Y0705192D03*
Y070716D03*
Y0709129D03*
Y0644168D03*
Y0659916D03*
Y0657948D03*
X0964162Y0654011D03*
X0948218Y0675664D03*
Y0673696D03*
X0964162Y0632357D03*
X0948218D03*
X0964162Y0634326D03*
Y0636294D03*
Y0638263D03*
Y0640231D03*
Y0644168D03*
Y0646137D03*
Y0648105D03*
Y0650074D03*
X0948218Y0654011D03*
X0964162Y0659916D03*
X0948218Y0695349D03*
X0964162Y06422D03*
Y0652042D03*
Y0661885D03*
Y0671727D03*
Y068157D03*
Y0691412D03*
Y0701255D03*
X0948218Y06422D03*
Y0652042D03*
Y0661885D03*
Y0671727D03*
Y068157D03*
Y0691412D03*
Y0701255D03*
Y0655979D03*
Y0693381D03*
X0964162Y0663853D03*
Y066779D03*
Y0655979D03*
Y0657948D03*
Y0665822D03*
Y0675664D03*
Y0673696D03*
X0948218Y0669759D03*
Y0665822D03*
Y066779D03*
Y0663853D03*
X0964162Y0669759D03*
X0948218Y0697318D03*
Y0699286D03*
X0964162Y0697318D03*
Y0699286D03*
Y0695349D03*
Y0683538D03*
Y0685507D03*
Y0677633D03*
Y0679601D03*
X0948218Y0636294D03*
Y0634326D03*
X0964162Y0693381D03*
Y0689444D03*
Y0687475D03*
X0948218Y0683538D03*
Y0687475D03*
Y0685507D03*
Y0689444D03*
Y0679601D03*
Y0650074D03*
Y0677633D03*
Y0648105D03*
Y0646137D03*
Y0638263D03*
Y0640231D03*
G54D70*
X0768699Y0713562D03*
Y0627932D03*
X095619Y0627928D03*
Y0713558D03*
G54D71*
X1181043Y0852D03*
X1173957D03*
X1269043Y06425D03*
X1261957D03*
X1269043Y06535D03*
X1261957D03*
X1250043Y08075D03*
X1242957D03*
X0964957Y0573D03*
X0972043D03*
X0917043Y0817D03*
X0909957D03*
X0786343Y0928D03*
X0779257D03*
X1019957Y0825D03*
X1027043D03*
G54D72*
X1166693Y0852D03*
X1163307D03*
X1235193Y0766D03*
X1231807D03*
X1235193Y07505D03*
X1231807D03*
X1235193Y0756D03*
X1231807D03*
X1235193Y07615D03*
X1231807D03*
X1263307Y06615D03*
X1266693D03*
X1263307Y06675D03*
X1266693D03*
X1263307Y06725D03*
X1266693D03*
X1263307Y0678D03*
X1266693D03*
X0967307Y0564D03*
X0970693D03*
G54D73*
X1029146Y0852D03*
X1034854D03*
G54D74*
X1274Y0709283D03*
Y0714716D03*
X12225Y0713283D03*
Y0718716D03*
X13Y0694216D03*
Y0688784D03*
X11995Y0734283D03*
Y0739716D03*
X08137Y0768317D03*
Y0762884D03*
X0662913Y0909717D03*
Y0904284D03*
X0683079D03*
Y0909717D03*
X0703246Y0904284D03*
Y0909717D03*
X0723413Y0904284D03*
Y0909717D03*
X12113Y0743784D03*
Y0749217D03*
X07924Y0913317D03*
Y0907883D03*
G54D75*
X0965827Y08865D03*
X0969173D03*
X0965827Y0879D03*
X0969173D03*
G54D76*
X08495Y0864622D03*
Y0848874D03*
Y0856748D03*
Y0841D03*
X0832Y0864622D03*
Y0856748D03*
Y0848874D03*
Y0841D03*
G54D140*
X0609Y0601D03*
Y0581D03*
X0629D03*
Y0601D03*
X0609Y07585D03*
Y07385D03*
X0629D03*
Y07585D03*
X0609Y0706D03*
Y0686D03*
X0629D03*
Y0706D03*
X0609Y06535D03*
Y06335D03*
X0629D03*
Y06535D03*
G54D147*
X090874Y05115D02*
Y052476D01*
X090876Y0524705D02*
Y052474D01*
X090874Y052476D02*
X090876Y052474D01*
X0896529Y05119D02*
Y0514495D01*
X089685Y0514173*
X0896481Y0514543D02*
X0896529Y0514495D01*
X0894587Y0525591D02*
X0896481Y0523696D01*
Y0514543D02*
Y0523696D01*
X0884718Y05119D02*
Y0514495D01*
X0885039Y0514173*
X088467Y0514543D02*
X0884718Y0514495D01*
X0878937Y0525591D02*
X0882776D01*
X088467Y0523696*
Y0514543D02*
Y0523696D01*
X0878937Y0525591D02*
X0880782Y0523746D01*
Y0514494D02*
Y0523746D01*
Y0514494D02*
X0881102Y0514173D01*
X0853561Y0524939D02*
X0853622Y0524878D01*
X0869266Y0518454D02*
X086937Y051835D01*
X0869266Y0518454D02*
Y0524013D01*
Y0514198D02*
Y0518454D01*
X086937Y05115D02*
Y051835D01*
X0868095Y0525184D02*
X0869266Y0524013D01*
X0862703Y0525184D02*
X0868095D01*
X0869266Y0514198D02*
X0869291Y0514173D01*
X0864183Y0525098D02*
X0865354Y0523927D01*
X0862789Y0525098D02*
X0864183D01*
X0862703Y0525184D02*
X0862789Y0525098D01*
X0865354Y0514173D02*
Y0523927D01*
X0845748Y05115D02*
Y0522953D01*
X0843701Y0525D02*
X0845748Y0522953D01*
X0833772Y0511665D02*
Y0524102D01*
X0832874Y0525D02*
X0833772Y0524102D01*
X083Y0525D02*
X0832874D01*
X080748Y0527559D02*
X0810236D01*
X0806299Y0526378D02*
X080748Y0527559D01*
X0806299Y0514173D02*
Y0526378D01*
X0790565Y0511565D02*
Y052487D01*
Y0511565D02*
X079063Y05115D01*
X0786693D02*
Y0524482D01*
X0783675Y0527175D02*
X0784D01*
X0782756Y05115D02*
Y0525931D01*
X0778819Y05115D02*
Y052439D01*
X0780523Y0526094D02*
X0782594D01*
X0778819Y052439D02*
X0780523Y0526094D01*
X0853561Y0511561D02*
X0853622Y05115D01*
X0853561Y0511561D02*
Y0524939D01*
X0782756Y0525931D02*
X0784Y0527175D01*
X0896529Y05119D02*
X0896929Y05115D01*
X0802441Y0524941D02*
X08025Y0525D01*
X0806378Y05115D02*
X0806685Y0511807D01*
X0833772Y0511665D02*
X0833937Y05115D01*
X0782594Y0526094D02*
X0783675Y0527175D01*
X0802441Y05115D02*
Y0524941D01*
X0884718Y05119D02*
X0885118Y05115D01*
X1235433Y0633465D02*
X1265748D01*
X1231Y0637898D02*
X1235433Y0633465D01*
X1231Y0637898D02*
Y0646406D01*
X1269043Y063676D02*
Y06425D01*
X1265748Y0633465D02*
X1269043Y063676D01*
X1273449Y0714716D02*
X1274016Y0715283D01*
X1228329Y0718522D02*
X1241478D01*
X1270232Y0700547D02*
Y0711799D01*
X1268185Y06985D02*
X1270232Y0700547D01*
X1262756Y06985D02*
X1268185D01*
X1270232Y0713932D02*
X1271016Y0714716D01*
X1270232Y0711799D02*
Y0713932D01*
X126906Y0710628D02*
X1270232Y0711799D01*
X1265671Y0710628D02*
X126906D01*
X1265Y0709957D02*
X1265671Y0710628D01*
X1271016Y0714716D02*
X1273449D01*
X1274*
X1270079Y0722441D02*
X1274016Y0718504D01*
Y0715283D02*
Y0718504D01*
X1257742Y0722441D02*
X1270079D01*
X12538Y07185D02*
X1257742Y0722441D01*
X1227165Y0715354D02*
Y0719685D01*
X1225512Y0713701D02*
X1227165Y0715354D01*
X1222917Y0713701D02*
X1225512D01*
X12225Y0713283D02*
X1222917Y0713701D01*
X1227165Y0719685D02*
X1228329Y0718522D01*
X1227165Y0719685D02*
Y0727559D01*
X1229106Y07295*
X1234244*
X123622Y0783071D02*
Y0791339D01*
X1224409Y0783071D02*
Y0791339D01*
X0920941Y0875429D02*
Y0883014D01*
X1248032Y0779528D02*
X1265933D01*
X1244488Y0775984D02*
X1248032Y0779528D01*
X123622Y0775984D02*
X1244488D01*
X1265933Y0779528D02*
X1267Y0780594D01*
X1224409Y0775984D02*
X123622D01*
X1224409Y0767717D02*
Y0775984D01*
X1226126Y0766D02*
X1231807D01*
X1224409Y0767717D02*
X1226126Y0766D01*
X1219004Y07505D02*
X12275D01*
X1217721Y0749217D02*
X1219004Y07505D01*
X12113Y0749217D02*
X1217721D01*
X1253937Y0793307D02*
X1262992D01*
X1250043Y0797201D02*
X1253937Y0793307D01*
X1250043Y0797201D02*
Y08075D01*
X1267Y0780594D02*
Y0789299D01*
X1262992Y0793307D02*
X1267Y0789299D01*
X1219094Y0871255D02*
X1221649D01*
X1218815Y0870976D02*
X1219094Y0871255D01*
X1218815Y08705D02*
Y0870976D01*
X1221649Y0871255D02*
X1224409Y0874016D01*
Y0909449*
X1219748Y091411D02*
X1224409Y0909449D01*
X117122Y091411D02*
X1219748D01*
X1233685Y0857D02*
X1237488D01*
X1241863Y0852625*
X1265779*
X1181043Y0847643D02*
Y0852D01*
X11787Y08453D02*
X1181043Y0847643D01*
X11654Y08453D02*
X11787D01*
X1163307Y0847393D02*
Y0852D01*
Y0847393D02*
X11654Y08453D01*
X1208434Y08558D02*
Y0856968D01*
Y08558D02*
X12141D01*
X12153Y0857*
X1219315*
Y08634*
X1218815Y08639D02*
X1219315Y08634D01*
X1218815Y08639D02*
Y08705D01*
X1211Y08747D02*
Y0882378D01*
X12068Y08705D02*
X1211Y08747D01*
X1202185Y08705D02*
X12068D01*
X1187028D02*
X1187815Y0871287D01*
X11795Y08705D02*
X1187028D01*
X117122Y087878D02*
X11795Y08705D01*
X117122Y087878D02*
Y0896D01*
X1129Y0854108D02*
Y092D01*
X1128Y0921D02*
X1129Y092D01*
X1125716Y0921D02*
X1128D01*
X1125716D02*
Y0925984D01*
X11237Y0928D02*
X1125716Y0925984D01*
X1076717Y0928D02*
X11237D01*
X10325Y0804807D02*
X10385D01*
X10265D02*
X10325D01*
X10155D02*
X1021D01*
X101D02*
X10155D01*
X1006425Y0784618D02*
X1014D01*
X10055Y0785543D02*
X1006425Y0784618D01*
X1014Y0779382D02*
X1014018Y07794D01*
X1016628*
X10178Y0780572*
Y07824*
X101968Y0784279*
X1021236*
X10225Y0785543*
X1033D02*
X10382D01*
X1039125Y0784618*
X10425*
X1233685Y0856213D02*
Y0857D01*
X1265779Y0852625D02*
X12725Y0859346D01*
X1273542Y0860389*
Y0865507D02*
X1289035Y0881D01*
X1273542Y0860389D02*
Y0865507D01*
X1271458Y0860389D02*
X12725Y0859346D01*
X1255965Y0881D02*
X1271458Y0865507D01*
Y0860389D02*
Y0865507D01*
X1187815Y08705D02*
Y0871287D01*
X1181043Y0852D02*
X11949D01*
X11985Y08556*
X11989Y0856D02*
X1202584D01*
X11985Y08556D02*
X11989Y0856D01*
X1208016Y0856551D02*
X1208434Y0856968D01*
X1208016Y0856D02*
Y0856551D01*
X1202384Y08562D02*
X1202584Y0856D01*
X10225Y0785543D02*
X1033D01*
X08715Y08525D02*
Y0856307D01*
X08665Y08505D02*
Y0851047D01*
X0863Y0853957D02*
X0863591D01*
X08665Y0851047*
X10225Y07729D02*
Y0778457D01*
X0832Y08365D02*
Y0841D01*
X1033Y07729D02*
Y0778457D01*
X10385Y0804807D02*
X10445D01*
X1021D02*
X10265D01*
X0980243Y08295D02*
X0996Y0813743D01*
X0943441Y0875429D02*
Y0876185D01*
X0948256Y0881*
X0953*
X0958Y0878854D02*
Y088535D01*
Y0878559D02*
Y0878854D01*
Y088535D02*
Y0885646D01*
X0953726Y0881077D02*
X0958Y088535D01*
X0953076Y0881077D02*
X0953726D01*
X0953Y0881D02*
X0953076Y0881077D01*
X0813Y0866728D02*
Y0866807D01*
Y08615D02*
Y0866728D01*
X082Y0864957D02*
X0820167Y0864789D01*
X0831833*
X0832Y0864622*
X0813Y0866728D02*
X0814772Y0864957D01*
X082*
X0724Y0925854D02*
X0728354D01*
X07285Y0926*
X0996Y0810265D02*
X1001947Y0804319D01*
X100213*
X1003Y0803449*
X0972257Y08295D02*
X0980243D01*
X096926Y0826503D02*
X0972257Y08295D01*
X1003Y080335D02*
Y0803449D01*
X0996Y0810265D02*
Y0813743D01*
X10445Y0804807D02*
X1044747Y0805054D01*
X1046505*
X1053Y0811549*
Y0816*
X1044Y0825D02*
X1053Y0816D01*
X1027043Y0825D02*
X1044D01*
X1003Y080335D02*
X1008622D01*
X101Y0804728*
Y0804807*
X0995Y0785543D02*
Y0795252D01*
X1003Y0803252*
Y080335*
X0995Y0785543D02*
X10055D01*
X10425Y0779382D02*
X1049382D01*
X11265Y0851608D02*
X1129Y0854108D01*
X11265Y08515D02*
Y0851608D01*
X1034854Y0852D02*
X1035278Y0851577D01*
X1126423*
X11265Y08515*
X1069716Y0921D02*
Y0921551D01*
X1070134Y0921968*
X1070685*
X1076717Y0928*
X12275Y07505D02*
X1231807D01*
X08715Y0859693D02*
X0871747Y0859446D01*
X0874054*
X08765Y0857*
X0862409Y0861043D02*
X0863D01*
X0858831Y0864622D02*
X0862409Y0861043D01*
X08495Y0864622D02*
X0858831D01*
X0864941Y0859693D02*
X08715D01*
X0863591Y0861043D02*
X0864941Y0859693D01*
X0863Y0861043D02*
X0863591D01*
X10185Y087785D02*
X102435D01*
X10245Y0878*
X10185Y0873283D02*
Y087785D01*
X1016685Y0871469D02*
X10185Y0873283D01*
X1016134Y0871469D02*
X1016685D01*
X1015716Y0871051D02*
X1016134Y0871469D01*
X1015716Y08705D02*
Y0871051D01*
X10095Y0877457D02*
X1009697Y0877654D01*
X1018303*
X10185Y087785*
X1283284Y0681449D02*
Y0682D01*
Y0667216D02*
Y0681449D01*
X12835Y06665D02*
Y0667D01*
X1283284Y0667216D02*
X12835Y0667D01*
X12415Y07185D02*
X12538D01*
X1241478Y0718522D02*
X12415Y07185D01*
X0813Y0866807D02*
X0813247Y0867054D01*
X0703833Y0925854D02*
X0724D01*
X0683667D02*
X0703833D01*
X06635D02*
X0683667D01*
X0955581Y0876914D02*
X095606D01*
X0957327Y0877886D02*
X0958Y0878559D01*
X0954527Y0870432D02*
Y087586D01*
X0955581Y0876914*
X0957032Y0877886D02*
X0957327D01*
X095606Y0876914D02*
X0957032Y0877886D01*
X0976727Y0848232D02*
X1032732D01*
X1034673Y0852D02*
X1034854D01*
X1034Y0851327D02*
X1034673Y0852D01*
X1034Y08495D02*
Y0851327D01*
X1032732Y0848232D02*
X1034Y08495D01*
X0954527Y0870432D02*
X0976727Y0848232D01*
X091797Y0885984D02*
Y0910537D01*
Y0885984D02*
X0920941Y0883014D01*
X09135Y0915008D02*
Y0922508D01*
Y0915008D02*
X091797Y0910537D01*
X0868441Y0875429D02*
Y0876185D01*
X0871257Y0879001*
X0877125*
X0879941Y0876185*
Y0875429D02*
Y0876185D01*
X09035Y0922508D02*
X09135D01*
X1231807Y07615D02*
Y0766D01*
Y0756D02*
Y07615D01*
Y07505D02*
Y0756D01*
X12285Y08705D02*
X1233185D01*
X1266693Y0678D02*
X1279835D01*
X1283284Y0681449*
X1266693Y06725D02*
Y0678D01*
Y06675D02*
Y06725D01*
Y06615D02*
Y06675D01*
X1269043Y06535D02*
Y065409D01*
X1266693Y0656441D02*
X1269043Y065409D01*
X1266693Y0656441D02*
Y06615D01*
X1269043Y06425D02*
Y06535D01*
G54D148*
X10714Y08799D02*
X1084845D01*
X1085Y0879745*
X1066Y08745D02*
X10714Y08799D01*
X1066Y0861D02*
Y08745D01*
X1085Y08D02*
Y082D01*
G54D149*
X0997728Y087625D02*
X0997742Y0876264D01*
X1008307*
X10095Y0877457*
G54D150*
X0810246Y0527362D03*
G54D151*
X0782628Y0527313D03*
G54D152*
X06285Y05373D03*
X13206Y05701D03*
X06294Y09156D03*
X13206Y09168D03*
G54D153*
X09775Y0913D03*
X0994823D03*
G54D154*
X08985Y0909004D03*
X09285D03*
G54D155*
X1028878Y0759928D03*
X1017067D03*
X1005256D03*
X0996988Y0589456D03*
Y0749298D03*
X1156831D03*
Y0669377D03*
Y0589456D03*
G54D156*
X117122Y0896D03*
Y091411D03*
X1255965Y0881D03*
Y0859346D03*
X12725Y0881D03*
Y0859346D03*
X1289035D03*
Y0881D03*
G54D157*
X1211Y0882378D03*
G54D158*
X1211Y0906D03*
G54D159*
X1192496Y0894189D03*
G54D160*
X0619Y0591D03*
Y07485D03*
Y0696D03*
Y06435D03*
G54D161*
X0898069Y0744247D03*
X089807Y0596253D03*
X081933D03*
X0768699Y0710117D03*
Y0631377D03*
X0819329Y0744247D03*
X095619Y0631373D03*
Y0710113D03*
G54D162*
X0803Y09156D03*
Y09056D03*
X07429Y09164D03*
Y09064D03*
G54D163*
X0803Y09256D03*
X07429Y09264D03*
G54D164*
X1255965Y090974D03*
X1289035D03*
G54D165*
X090876Y0524705D03*
X0894587Y0525591D03*
X0853622Y0524878D03*
X0843701Y0525D03*
X08422Y05285D03*
X08398D03*
X0806693Y0525984D03*
Y0529134D03*
X0810236D03*
X0814173D03*
X0810236Y0525984D03*
X0814173D03*
X079063Y052487D03*
X0782283Y0525984D03*
X0784252D03*
X0786221D03*
X0782283Y0529134D03*
X0784252D03*
X0786221D03*
X0876Y0529D03*
X08736D03*
X08898Y05287D03*
X08025Y0525D03*
X08595Y05288D03*
X0862703Y0525184D03*
X0788746Y0652046D03*
X0878937Y0525591D03*
X083Y0525D03*
X08566Y05289D03*
X08922Y05287D03*
X0887205Y0525689D03*
X07788Y05359D03*
X0891732Y0814961D03*
X0885827D03*
X0883071D03*
X0888976D03*
X0891732Y0811811D03*
X0885827D03*
X0883071D03*
X0888976D03*
X0891732Y081811D03*
X0885827D03*
X0883071D03*
X0888976D03*
Y082126D03*
X0883071D03*
X0885827D03*
X0891732D03*
X1224409Y0791339D03*
X126378Y0813386D03*
X1125716Y0909284D03*
X1033Y07729D03*
X1049382Y0779382D03*
X082219Y075881D03*
X082425Y076175D03*
X0826219Y0746781D03*
X09562Y07062D03*
X0931933Y0683D03*
X0940462Y06809D03*
X0942941Y0687488D03*
X0996Y06556D03*
X0781294Y0667794D03*
X0787009Y0681574D03*
X0755836Y0707164D03*
X11985Y08556D03*
X09592Y08142D03*
Y07896D03*
X08975Y0805D03*
X0907Y07985D03*
X1004Y08669D03*
X0982Y0881D03*
X07779Y09331D03*
X09581Y06666D03*
X08321Y07219D03*
X11568Y07218D03*
X08774Y07572D03*
X07712Y06993D03*
X08693Y07293D03*
X08685Y06485D03*
X10055Y06515D03*
X08887Y08382D03*
X0838Y08485D03*
X08375Y06945D03*
X09795Y06844D03*
X08505Y05941D03*
X08656Y06096D03*
X09821Y08766D03*
X12325Y0827D03*
X09735Y08265D03*
X0976402Y0667004D03*
X08314Y0759D03*
X07662Y06796D03*
X08774Y06098D03*
X09386Y09226D03*
X10263Y08139D03*
X0971Y07D03*
X09401Y0671759D03*
X0849Y0724D03*
X11625D03*
X08615Y07465D03*
X08617Y06774D03*
X10055Y068D03*
X07705Y06599D03*
X1085Y08D03*
X12295Y08125D03*
X0993D03*
X09915Y0654D03*
X08716Y08164D03*
X08717Y08329D03*
X09048Y08159D03*
X0813Y08742D03*
X0918742Y06718D03*
X09188Y07974D03*
X08414Y08127D03*
X08479Y07417D03*
X08401Y06093D03*
X1012Y0852D03*
X08485Y07665D03*
X0903536Y0821364D03*
X10199Y08139D03*
X09585Y06518D03*
X08676Y07572D03*
X07662Y06403D03*
X08137Y07757D03*
X10125Y06755D03*
X08595Y06738D03*
X0859Y0744D03*
X12617Y08036D03*
X10143Y08139D03*
X08694Y05952D03*
X08245Y0854D03*
X0829Y0692D03*
X09545Y06895D03*
X10055Y07726D03*
X08485Y077D03*
X08715Y08525D03*
X08302Y05938D03*
X08862Y07301D03*
X07666Y06895D03*
X08845Y05399D03*
X0881D03*
X0888285Y0583251D03*
X08852Y05824D03*
X07239Y07004D03*
X0971Y06925D03*
X09404Y06577D03*
X0857Y07285D03*
Y06794D03*
X09935Y0682D03*
X07712Y06698D03*
X08807Y07907D03*
X08907D03*
X10122Y0669D03*
X08303Y06097D03*
X10059Y08139D03*
X08665Y08505D03*
X10225Y07729D03*
X08714Y07924D03*
X08395Y07416D03*
X09723Y06422D03*
X08577Y07573D03*
X07662Y06501D03*
X09545Y06995D03*
X08961Y08415D03*
X12447Y08013D03*
X07682Y09083D03*
X09633Y0564D03*
X0825Y08265D03*
X09365Y08277D03*
X09359Y08054D03*
X08774Y07433D03*
X07665Y06993D03*
X1003Y08788D03*
X12467Y08235D03*
X10324Y08139D03*
X10468D03*
X09545Y06845D03*
X09397Y06465D03*
X08566Y07416D03*
X1003Y0741D03*
X07707Y06403D03*
X07709Y06796D03*
X07548Y09233D03*
X09188Y08218D03*
X07717Y0933D03*
X08244Y07283D03*
X08924Y05957D03*
X0971Y0677D03*
X0854Y06759D03*
X08625Y0841D03*
X08466Y0746D03*
X07661Y06599D03*
X08892Y06099D03*
X09545Y06945D03*
X09268Y06809D03*
X09265Y0861D03*
X1066D03*
X09959Y06675D03*
X09951Y07728D03*
X08601Y05938D03*
X1227257Y0823D03*
X09797Y08239D03*
X09794Y06695D03*
X08464Y07984D03*
X08676Y07315D03*
X08597Y06095D03*
X07252Y07486D03*
X09709Y06717D03*
X0954Y06417D03*
X08872Y0757D03*
X07709Y06501D03*
X07712Y06894D03*
X08875Y07903D03*
X09987Y06715D03*
X08404Y08299D03*
X10105Y08139D03*
X12639Y08345D03*
X0832Y08365D03*
X08622Y0788D03*
X08879Y09225D03*
X09361Y07892D03*
X084Y07583D03*
X07661Y06698D03*
X08833Y06099D03*
X08753Y07906D03*
X08249Y08745D03*
X08406Y07796D03*
X08572Y07312D03*
X08499Y06094D03*
X0774Y09114D03*
X08561Y09287D03*
X0745Y08151D03*
X07431Y08561D03*
X07576Y09129D03*
X07894Y09022D03*
X08235Y09021D03*
X08281Y09221D03*
X09871Y08113D03*
X09482Y08107D03*
X08812Y07605D03*
X09614Y07591D03*
X09613Y0849D03*
X09482Y08301D03*
X0953302Y0832298D03*
X09335Y08D03*
X09735Y08346D03*
X09644Y08297D03*
X09385Y08451D03*
X09427Y08461D03*
X09349Y08452D03*
X09708Y08076D03*
X08425Y0855D03*
X0857Y0849D03*
X07884Y06697D03*
X09215Y0666528D03*
X0879Y0862D03*
X0958Y06715D03*
X0901Y054D03*
X11724Y0856D03*
X11667Y0855D03*
X08405Y05941D03*
X09594Y05686D03*
X08469Y05941D03*
X08715Y06097D03*
X12619Y06376D03*
X12539Y06535D03*
X12593Y06616D03*
Y06676D03*
Y06726D03*
X12592Y06781D03*
X12676Y06832D03*
X1269Y06885D03*
X13042Y06961D03*
X1294Y07099D03*
X12598Y0718D03*
X12386Y07115D03*
X12039Y07175D03*
X11995Y07438D03*
X12265Y07395D03*
X12389Y07457D03*
X12388Y07505D03*
X12387Y0756D03*
X12388Y07614D03*
X12389Y07661D03*
X123622Y0791339D03*
X10901Y09207D03*
X10378Y0921D03*
X09768Y09027D03*
X10076Y08896D03*
X10185Y08888D03*
X10422Y08139D03*
X09321Y08305D03*
X0909Y07916D03*
X09023Y07972D03*
X09009Y07901D03*
X08851Y08791D03*
X08715Y08733D03*
X09522Y08664D03*
X0926Y08792D03*
X07233Y06476D03*
X07247Y05946D03*
X06645Y05794D03*
X06646Y06032D03*
X06645Y06318D03*
X06644Y06555D03*
X06645Y06843D03*
Y07077D03*
Y07369D03*
X0664412Y0759783D03*
X08717Y07297D03*
X08622Y05978D03*
X08933Y0729D03*
X08734Y05827D03*
X08783Y0579D03*
X08656Y07295D03*
X08658Y05985D03*
X09885Y0657D03*
X084Y07318D03*
X07556Y06323D03*
X08582Y05817D03*
X08794Y07311D03*
X08976Y07291D03*
X08466Y07295D03*
X087657Y0582263D03*
X08822Y05792D03*
X08727Y05947D03*
X09855Y06515D03*
X09395Y0636726D03*
X09289Y06975D03*
X07875Y07075D03*
X09383Y06875D03*
X08692Y05985D03*
X0873525Y0599177D03*
X08911Y07432D03*
X08949Y07625D03*
X08636Y07278D03*
X084Y07287D03*
X088Y05978D03*
X0937Y0639D03*
X08441Y07286D03*
X09243Y06665D03*
X0954Y06445D03*
X08939Y0746D03*
X0761Y07125D03*
X08588Y05979D03*
X0937Y0634D03*
X0771Y0654D03*
X08616Y05817D03*
X09825Y06485D03*
X08885Y07435D03*
X07745Y0713D03*
X0882941Y0599141D03*
X07782Y06301D03*
X0939744Y0641526D03*
X08832Y07267D03*
X0957Y07947D03*
X09221Y08239D03*
X09243Y08297D03*
X08197Y06302D03*
X08196Y08204D03*
X08495Y08086D03*
X08493Y0632D03*
X0841Y08198D03*
X08581Y08292D03*
X08582Y08204D03*
X08516Y07467D03*
X09333Y07267D03*
X09489Y07345D03*
X0841935Y07625D03*
X06995Y0591D03*
X08437Y06441D03*
X06999Y06434D03*
X084Y06971D03*
X07Y0696D03*
X07011Y07485D03*
X08634Y0662D03*
X08657Y06644D03*
X08345Y05434D03*
X08369D03*
X0876532Y0598081D03*
X0897Y05398D03*
X08695Y054D03*
X08655Y05401D03*
X0846Y05402D03*
X08502Y05401D03*
X0957Y0759D03*
X07875Y08605D03*
X07745Y08665D03*
X09415Y0864D03*
X0754Y08625D03*
X0923Y086D03*
X07565D03*
X0953Y0881D03*
X0921D03*
X0871257Y0879001D03*
X0813Y08615D03*
X08075Y089D03*
X08074Y064156D03*
X0805Y0639D03*
Y08875D03*
X0802Y0884D03*
X08019Y063656D03*
X07285Y0926D03*
X07995Y0882D03*
Y0634D03*
X08225Y0851D03*
X0952Y08485D03*
X11265Y08515D03*
X12275Y07505D03*
X0867Y08665D03*
X08765Y0857D03*
X09562Y07037D03*
X0898354Y08755D03*
X0969D03*
X09005Y08835D03*
X0969Y0884D03*
X10245Y0878D03*
X08885Y06565D03*
X0891Y0654D03*
X09985Y06555D03*
X08265Y0651D03*
X10025Y0655D03*
X0871Y06595D03*
X1017Y06605D03*
X1014146Y0662756D03*
X10125Y06655D03*
X09715Y06679D03*
X12835Y06665D03*
X12415Y07185D03*
X1229957Y08203D03*
X1233Y08155D03*
X1074487Y0911987D03*
X0777Y0916D03*
X09495Y0909D03*
X09845Y08155D03*
X0982Y0818D03*
X0979Y08205D03*
X1243Y08195D03*
X1234491Y0833508D03*
X12435Y08295D03*
X09293Y08348D03*
X124Y08375D03*
X1243773Y084D03*
X1247Y0843D03*
X125Y0846D03*
X0946D03*
X0784Y08705D03*
X12285D03*
M02*